G04 ================== begin FILE IDENTIFICATION RECORD ==================*
G04 Layout Name:  12004-1.brd*
G04 Film Name:    TSMD*
G04 File Format:  Gerber RS274X*
G04 File Origin:  Cadence Allegro 16.2-S033*
G04 Origin Date:  Tue Oct 16 14:35:55 2012*
G04 *
G04 Layer:  VIA CLASS/PASTEMASK_TOP*
G04 Layer:  PIN/PASTEMASK_TOP*
G04 Layer:  PACKAGE GEOMETRY/PASTEMASK_TOP*
G04 Layer:  DRAWING FORMAT/LAYER_PCB_STORY*
G04 Layer:  DRAWING FORMAT/LAYER_PAST_T*
G04 Layer:  BOARD GEOMETRY/PANEL_OUTLINE*
G04 *
G04 Offset:    (0.00 0.00)*
G04 Mirror:    No*
G04 Mode:      Positive*
G04 Rotation:  0*
G04 FullContactRelief:  No*
G04 UndefLineWidth:     6.00*
G04 ================== end FILE IDENTIFICATION RECORD ====================*
%FSLAX35Y35*MOIN*%
%IR0*IPPOS*OFA0.00000B0.00000*MIA0B0*SFA1.00000B1.00000*%
%AMMACRO40*
4,1,40,.017,-.013,
.017,.013,
.016939,.013695,
.016759,.014368,
.016464,.015,
.016064,.015571,
.015571,.016064,
.015,.016464,
.014368,.016759,
.013695,.016939,
.013,.017,
-.013,.017,
-.013695,.016939,
-.014368,.016759,
-.015,.016464,
-.015571,.016064,
-.016064,.015571,
-.016464,.015,
-.016759,.014368,
-.016939,.013695,
-.017,.013,
-.017,-.013,
-.016939,-.013695,
-.016759,-.014368,
-.016464,-.015,
-.016064,-.015571,
-.015571,-.016064,
-.015,-.016464,
-.014368,-.016759,
-.013695,-.016939,
-.013,-.017,
.013,-.017,
.013695,-.016939,
.014368,-.016759,
.015,-.016464,
.015571,-.016064,
.016064,-.015571,
.016464,-.015,
.016759,-.014368,
.016939,-.013695,
.017,-.013,
0.0*
%
%ADD40MACRO40*%
%AMMACRO35*
4,1,40,.013,.017,
-.013,.017,
-.013695,.016939,
-.014368,.016759,
-.015,.016464,
-.015571,.016064,
-.016064,.015571,
-.016464,.015,
-.016759,.014368,
-.016939,.013695,
-.017,.013,
-.017,-.013,
-.016939,-.013695,
-.016759,-.014368,
-.016464,-.015,
-.016064,-.015571,
-.015571,-.016064,
-.015,-.016464,
-.014368,-.016759,
-.013695,-.016939,
-.013,-.017,
.013,-.017,
.013695,-.016939,
.014368,-.016759,
.015,-.016464,
.015571,-.016064,
.016064,-.015571,
.016464,-.015,
.016759,-.014368,
.016939,-.013695,
.017,-.013,
.017,.013,
.016939,.013695,
.016759,.014368,
.016464,.015,
.016064,.015571,
.015571,.016064,
.015,.016464,
.014368,.016759,
.013695,.016939,
.013,.017,
0.0*
%
%ADD35MACRO35*%
%AMMACRO66*
4,1,3,.025,.0125,
0.0,-.0125,
-.025,.0125,
.025,.0125,
0.0*
%
%ADD66MACRO66*%
%ADD70R,.045X.11*%
%ADD42R,.11X.055*%
%AMMACRO59*
4,1,3,0.0,-.0125,
-.025,.0125,
.025,.0125,
0.0,-.0125,
0.0*
%
%ADD59MACRO59*%
%ADD28C,.02*%
%ADD50R,.064X.136*%
%ADD29C,.018*%
%ADD46R,.167X.09*%
%ADD11R,.05X.05*%
%AMMACRO19*
4,1,40,.011,-.007,
.011,.007,
.010939,.007695,
.010759,.008368,
.010464,.009,
.010064,.009571,
.009571,.010064,
.009,.010464,
.008368,.010759,
.007695,.010939,
.007,.011,
-.007,.011,
-.007695,.010939,
-.008368,.010759,
-.009,.010464,
-.009571,.010064,
-.010064,.009571,
-.010464,.009,
-.010759,.008368,
-.010939,.007695,
-.011,.007,
-.011,-.007,
-.010939,-.007695,
-.010759,-.008368,
-.010464,-.009,
-.010064,-.009571,
-.009571,-.010064,
-.009,-.010464,
-.008368,-.010759,
-.007695,-.010939,
-.007,-.011,
.007,-.011,
.007695,-.010939,
.008368,-.010759,
.009,-.010464,
.009571,-.010064,
.010064,-.009571,
.010464,-.009,
.010759,-.008368,
.010939,-.007695,
.011,-.007,
0.0*
%
%ADD19MACRO19*%
%AMMACRO17*
4,1,40,.007,.011,
-.007,.011,
-.007695,.010939,
-.008368,.010759,
-.009,.010464,
-.009571,.010064,
-.010064,.009571,
-.010464,.009,
-.010759,.008368,
-.010939,.007695,
-.011,.007,
-.011,-.007,
-.010939,-.007695,
-.010759,-.008368,
-.010464,-.009,
-.010064,-.009571,
-.009571,-.010064,
-.009,-.010464,
-.008368,-.010759,
-.007695,-.010939,
-.007,-.011,
.007,-.011,
.007695,-.010939,
.008368,-.010759,
.009,-.010464,
.009571,-.010064,
.010064,-.009571,
.010464,-.009,
.010759,-.008368,
.010939,-.007695,
.011,-.007,
.011,.007,
.010939,.007695,
.010759,.008368,
.010464,.009,
.010064,.009571,
.009571,.010064,
.009,.010464,
.008368,.010759,
.007695,.010939,
.007,.011,
0.0*
%
%ADD17MACRO17*%
%AMMACRO24*
4,1,40,-.012,.008,
-.012,-.008,
-.011939,-.008695,
-.011759,-.009368,
-.011464,-.01,
-.011064,-.010571,
-.010571,-.011064,
-.01,-.011464,
-.009368,-.011759,
-.008695,-.011939,
-.008,-.012,
.008,-.012,
.008695,-.011939,
.009368,-.011759,
.01,-.011464,
.010571,-.011064,
.011064,-.010571,
.011464,-.01,
.011759,-.009368,
.011939,-.008695,
.012,-.008,
.012,.008,
.011939,.008695,
.011759,.009368,
.011464,.01,
.011064,.010571,
.010571,.011064,
.01,.011464,
.009368,.011759,
.008695,.011939,
.008,.012,
-.008,.012,
-.008695,.011939,
-.009368,.011759,
-.01,.011464,
-.010571,.011064,
-.011064,.010571,
-.011464,.01,
-.011759,.009368,
-.011939,.008695,
-.012,.008,
0.0*
%
%ADD24MACRO24*%
%AMMACRO52*
4,1,40,.008,.012,
-.008,.012,
-.008695,.011939,
-.009368,.011759,
-.01,.011464,
-.010571,.011064,
-.011064,.010571,
-.011464,.01,
-.011759,.009368,
-.011939,.008695,
-.012,.008,
-.012,-.008,
-.011939,-.008695,
-.011759,-.009368,
-.011464,-.01,
-.011064,-.010571,
-.010571,-.011064,
-.01,-.011464,
-.009368,-.011759,
-.008695,-.011939,
-.008,-.012,
.008,-.012,
.008695,-.011939,
.009368,-.011759,
.01,-.011464,
.010571,-.011064,
.011064,-.010571,
.011464,-.01,
.011759,-.009368,
.011939,-.008695,
.012,-.008,
.012,.008,
.011939,.008695,
.011759,.009368,
.011464,.01,
.011064,.010571,
.010571,.011064,
.01,.011464,
.009368,.011759,
.008695,.011939,
.008,.012,
0.0*
%
%ADD52MACRO52*%
%AMMACRO37*
4,1,40,-.013,-.017,
.013,-.017,
.013695,-.016939,
.014368,-.016759,
.015,-.016464,
.015571,-.016064,
.016064,-.015571,
.016464,-.015,
.016759,-.014368,
.016939,-.013695,
.017,-.013,
.017,.013,
.016939,.013695,
.016759,.014368,
.016464,.015,
.016064,.015571,
.015571,.016064,
.015,.016464,
.014368,.016759,
.013695,.016939,
.013,.017,
-.013,.017,
-.013695,.016939,
-.014368,.016759,
-.015,.016464,
-.015571,.016064,
-.016064,.015571,
-.016464,.015,
-.016759,.014368,
-.016939,.013695,
-.017,.013,
-.017,-.013,
-.016939,-.013695,
-.016759,-.014368,
-.016464,-.015,
-.016064,-.015571,
-.015571,-.016064,
-.015,-.016464,
-.014368,-.016759,
-.013695,-.016939,
-.013,-.017,
0.0*
%
%ADD37MACRO37*%
%AMMACRO48*
4,1,40,-.017,.013,
-.017,-.013,
-.016939,-.013695,
-.016759,-.014368,
-.016464,-.015,
-.016064,-.015571,
-.015571,-.016064,
-.015,-.016464,
-.014368,-.016759,
-.013695,-.016939,
-.013,-.017,
.013,-.017,
.013695,-.016939,
.014368,-.016759,
.015,-.016464,
.015571,-.016064,
.016064,-.015571,
.016464,-.015,
.016759,-.014368,
.016939,-.013695,
.017,-.013,
.017,.013,
.016939,.013695,
.016759,.014368,
.016464,.015,
.016064,.015571,
.015571,.016064,
.015,.016464,
.014368,.016759,
.013695,.016939,
.013,.017,
-.013,.017,
-.013695,.016939,
-.014368,.016759,
-.015,.016464,
-.015571,.016064,
-.016064,.015571,
-.016464,.015,
-.016759,.014368,
-.016939,.013695,
-.017,.013,
0.0*
%
%ADD48MACRO48*%
%AMMACRO20*
4,1,40,.011,-.007,
.011,.007,
.010939,.007695,
.010759,.008368,
.010464,.009,
.010064,.009571,
.009571,.010064,
.009,.010464,
.008368,.010759,
.007695,.010939,
.007,.011,
-.007,.011,
-.007695,.010939,
-.008368,.010759,
-.009,.010464,
-.009571,.010064,
-.010064,.009571,
-.010464,.009,
-.010759,.008368,
-.010939,.007695,
-.011,.007,
-.011,-.007,
-.010939,-.007695,
-.010759,-.008368,
-.010464,-.009,
-.010064,-.009571,
-.009571,-.010064,
-.009,-.010464,
-.008368,-.010759,
-.007695,-.010939,
-.007,-.011,
.007,-.011,
.007695,-.010939,
.008368,-.010759,
.009,-.010464,
.009571,-.010064,
.010064,-.009571,
.010464,-.009,
.010759,-.008368,
.010939,-.007695,
.011,-.007,
0.0*
%
%ADD20MACRO20*%
%AMMACRO18*
4,1,40,.007,.011,
-.007,.011,
-.007695,.010939,
-.008368,.010759,
-.009,.010464,
-.009571,.010064,
-.010064,.009571,
-.010464,.009,
-.010759,.008368,
-.010939,.007695,
-.011,.007,
-.011,-.007,
-.010939,-.007695,
-.010759,-.008368,
-.010464,-.009,
-.010064,-.009571,
-.009571,-.010064,
-.009,-.010464,
-.008368,-.010759,
-.007695,-.010939,
-.007,-.011,
.007,-.011,
.007695,-.010939,
.008368,-.010759,
.009,-.010464,
.009571,-.010064,
.010064,-.009571,
.010464,-.009,
.010759,-.008368,
.010939,-.007695,
.011,-.007,
.011,.007,
.010939,.007695,
.010759,.008368,
.010464,.009,
.010064,.009571,
.009571,.010064,
.009,.010464,
.008368,.010759,
.007695,.010939,
.007,.011,
0.0*
%
%ADD18MACRO18*%
%AMMACRO64*
4,1,20,.0635,-.1075,
.049,-.1075,
.049,-.118,
.0395,-.118,
.0395,-.1075,
-.0395,-.1075,
-.0395,-.118,
-.049,-.118,
-.049,-.1075,
-.0635,-.1075,
-.0635,.1075,
-.049,.1075,
-.049,.118,
-.0395,.118,
-.0395,.1075,
.0395,.1075,
.0395,.118,
.049,.118,
.049,.1075,
.0635,.1075,
.0635,-.1075,
0.0*
%
%ADD64MACRO64*%
%AMMACRO23*
4,1,40,-.012,.008,
-.012,-.008,
-.011939,-.008695,
-.011759,-.009368,
-.011464,-.01,
-.011064,-.010571,
-.010571,-.011064,
-.01,-.011464,
-.009368,-.011759,
-.008695,-.011939,
-.008,-.012,
.008,-.012,
.008695,-.011939,
.009368,-.011759,
.01,-.011464,
.010571,-.011064,
.011064,-.010571,
.011464,-.01,
.011759,-.009368,
.011939,-.008695,
.012,-.008,
.012,.008,
.011939,.008695,
.011759,.009368,
.011464,.01,
.011064,.010571,
.010571,.011064,
.01,.011464,
.009368,.011759,
.008695,.011939,
.008,.012,
-.008,.012,
-.008695,.011939,
-.009368,.011759,
-.01,.011464,
-.010571,.011064,
-.011064,.010571,
-.011464,.01,
-.011759,.009368,
-.011939,.008695,
-.012,.008,
0.0*
%
%ADD23MACRO23*%
%AMMACRO51*
4,1,40,.008,.012,
-.008,.012,
-.008695,.011939,
-.009368,.011759,
-.01,.011464,
-.010571,.011064,
-.011064,.010571,
-.011464,.01,
-.011759,.009368,
-.011939,.008695,
-.012,.008,
-.012,-.008,
-.011939,-.008695,
-.011759,-.009368,
-.011464,-.01,
-.011064,-.010571,
-.010571,-.011064,
-.01,-.011464,
-.009368,-.011759,
-.008695,-.011939,
-.008,-.012,
.008,-.012,
.008695,-.011939,
.009368,-.011759,
.01,-.011464,
.010571,-.011064,
.011064,-.010571,
.011464,-.01,
.011759,-.009368,
.011939,-.008695,
.012,-.008,
.012,.008,
.011939,.008695,
.011759,.009368,
.011464,.01,
.011064,.010571,
.010571,.011064,
.01,.011464,
.009368,.011759,
.008695,.011939,
.008,.012,
0.0*
%
%ADD51MACRO51*%
%AMMACRO38*
4,1,40,-.013,-.017,
.013,-.017,
.013695,-.016939,
.014368,-.016759,
.015,-.016464,
.015571,-.016064,
.016064,-.015571,
.016464,-.015,
.016759,-.014368,
.016939,-.013695,
.017,-.013,
.017,.013,
.016939,.013695,
.016759,.014368,
.016464,.015,
.016064,.015571,
.015571,.016064,
.015,.016464,
.014368,.016759,
.013695,.016939,
.013,.017,
-.013,.017,
-.013695,.016939,
-.014368,.016759,
-.015,.016464,
-.015571,.016064,
-.016064,.015571,
-.016464,.015,
-.016759,.014368,
-.016939,.013695,
-.017,.013,
-.017,-.013,
-.016939,-.013695,
-.016759,-.014368,
-.016464,-.015,
-.016064,-.015571,
-.015571,-.016064,
-.015,-.016464,
-.014368,-.016759,
-.013695,-.016939,
-.013,-.017,
0.0*
%
%ADD38MACRO38*%
%AMMACRO49*
4,1,40,-.017,.013,
-.017,-.013,
-.016939,-.013695,
-.016759,-.014368,
-.016464,-.015,
-.016064,-.015571,
-.015571,-.016064,
-.015,-.016464,
-.014368,-.016759,
-.013695,-.016939,
-.013,-.017,
.013,-.017,
.013695,-.016939,
.014368,-.016759,
.015,-.016464,
.015571,-.016064,
.016064,-.015571,
.016464,-.015,
.016759,-.014368,
.016939,-.013695,
.017,-.013,
.017,.013,
.016939,.013695,
.016759,.014368,
.016464,.015,
.016064,.015571,
.015571,.016064,
.015,.016464,
.014368,.016759,
.013695,.016939,
.013,.017,
-.013,.017,
-.013695,.016939,
-.014368,.016759,
-.015,.016464,
-.015571,.016064,
-.016064,.015571,
-.016464,.015,
-.016759,.014368,
-.016939,.013695,
-.017,.013,
0.0*
%
%ADD49MACRO49*%
%ADD68R,.06X.02*%
%AMMACRO55*
4,1,3,-.025,-.0125,
0.0,.0125,
.025,-.0125,
-.025,-.0125,
0.0*
%
%ADD55MACRO55*%
%AMMACRO65*
4,1,3,0.0,.0125,
.025,-.0125,
-.025,-.0125,
0.0,.0125,
0.0*
%
%ADD65MACRO65*%
%ADD12R,.06X.012*%
%ADD36O,.071X.014*%
%ADD73R,.04X.016*%
%ADD71R,.06X.014*%
%ADD53R,.044X.012*%
%ADD76R,.014X.042*%
%ADD75R,.042X.014*%
%ADD67R,.014X.06*%
%ADD45R,.114X.128*%
%ADD26R,.045X.03*%
%ADD60R,.08X.05*%
%ADD57R,.038X.012*%
%ADD56R,.012X.038*%
%ADD10C,.14*%
%ADD77R,.05X.065*%
%ADD61R,.073X.07*%
%ADD39R,.065X.05*%
%ADD72R,.065X.025*%
%ADD69R,.09X.09*%
%AMMACRO58*
4,1,12,-.0405,.0405,
-.013,.0405,
-.013,.07,
.013,.07,
.013,.0405,
.0405,.0405,
.0405,-.0405,
.013,-.0405,
.013,-.07,
-.013,-.07,
-.013,-.0405,
-.0405,-.0405,
-.0405,.0405,
0.0*
%
%ADD58MACRO58*%
%ADD44R,.025X.065*%
%ADD30R,.045X.055*%
%ADD63R,.083X.035*%
%ADD54R,.074X.054*%
%ADD34R,.055X.045*%
%ADD27R,.016X.048*%
%ADD62R,.073X.065*%
%ADD43R,.095X.09*%
%ADD21R,.038X.095*%
%ADD47R,.087X.047*%
%ADD74R,.128X.128*%
%AMMACRO33*
4,1,40,-.008,-.012,
.008,-.012,
.008695,-.011939,
.009368,-.011759,
.01,-.011464,
.010571,-.011064,
.011064,-.010571,
.011464,-.01,
.011759,-.009368,
.011939,-.008695,
.012,-.008,
.012,.008,
.011939,.008695,
.011759,.009368,
.011464,.01,
.011064,.010571,
.010571,.011064,
.01,.011464,
.009368,.011759,
.008695,.011939,
.008,.012,
-.008,.012,
-.008695,.011939,
-.009368,.011759,
-.01,.011464,
-.010571,.011064,
-.011064,.010571,
-.011464,.01,
-.011759,.009368,
-.011939,.008695,
-.012,.008,
-.012,-.008,
-.011939,-.008695,
-.011759,-.009368,
-.011464,-.01,
-.011064,-.010571,
-.010571,-.011064,
-.01,-.011464,
-.009368,-.011759,
-.008695,-.011939,
-.008,-.012,
0.0*
%
%ADD33MACRO33*%
%AMMACRO22*
4,1,40,.012,-.008,
.012,.008,
.011939,.008695,
.011759,.009368,
.011464,.01,
.011064,.010571,
.010571,.011064,
.01,.011464,
.009368,.011759,
.008695,.011939,
.008,.012,
-.008,.012,
-.008695,.011939,
-.009368,.011759,
-.01,.011464,
-.010571,.011064,
-.011064,.010571,
-.011464,.01,
-.011759,.009368,
-.011939,.008695,
-.012,.008,
-.012,-.008,
-.011939,-.008695,
-.011759,-.009368,
-.011464,-.01,
-.011064,-.010571,
-.010571,-.011064,
-.01,-.011464,
-.009368,-.011759,
-.008695,-.011939,
-.008,-.012,
.008,-.012,
.008695,-.011939,
.009368,-.011759,
.01,-.011464,
.010571,-.011064,
.011064,-.010571,
.011464,-.01,
.011759,-.009368,
.011939,-.008695,
.012,-.008,
0.0*
%
%ADD22MACRO22*%
%AMMACRO15*
4,1,40,-.007,-.011,
.007,-.011,
.007695,-.010939,
.008368,-.010759,
.009,-.010464,
.009571,-.010064,
.010064,-.009571,
.010464,-.009,
.010759,-.008368,
.010939,-.007695,
.011,-.007,
.011,.007,
.010939,.007695,
.010759,.008368,
.010464,.009,
.010064,.009571,
.009571,.010064,
.009,.010464,
.008368,.010759,
.007695,.010939,
.007,.011,
-.007,.011,
-.007695,.010939,
-.008368,.010759,
-.009,.010464,
-.009571,.010064,
-.010064,.009571,
-.010464,.009,
-.010759,.008368,
-.010939,.007695,
-.011,.007,
-.011,-.007,
-.010939,-.007695,
-.010759,-.008368,
-.010464,-.009,
-.010064,-.009571,
-.009571,-.010064,
-.009,-.010464,
-.008368,-.010759,
-.007695,-.010939,
-.007,-.011,
0.0*
%
%ADD15MACRO15*%
%AMMACRO13*
4,1,40,-.011,.007,
-.011,-.007,
-.010939,-.007695,
-.010759,-.008368,
-.010464,-.009,
-.010064,-.009571,
-.009571,-.010064,
-.009,-.010464,
-.008368,-.010759,
-.007695,-.010939,
-.007,-.011,
.007,-.011,
.007695,-.010939,
.008368,-.010759,
.009,-.010464,
.009571,-.010064,
.010064,-.009571,
.010464,-.009,
.010759,-.008368,
.010939,-.007695,
.011,-.007,
.011,.007,
.010939,.007695,
.010759,.008368,
.010464,.009,
.010064,.009571,
.009571,.010064,
.009,.010464,
.008368,.010759,
.007695,.010939,
.007,.011,
-.007,.011,
-.007695,.010939,
-.008368,.010759,
-.009,.010464,
-.009571,.010064,
-.010064,.009571,
-.010464,.009,
-.010759,.008368,
-.010939,.007695,
-.011,.007,
0.0*
%
%ADD13MACRO13*%
%AMMACRO41*
4,1,40,.017,-.013,
.017,.013,
.016939,.013695,
.016759,.014368,
.016464,.015,
.016064,.015571,
.015571,.016064,
.015,.016464,
.014368,.016759,
.013695,.016939,
.013,.017,
-.013,.017,
-.013695,.016939,
-.014368,.016759,
-.015,.016464,
-.015571,.016064,
-.016064,.015571,
-.016464,.015,
-.016759,.014368,
-.016939,.013695,
-.017,.013,
-.017,-.013,
-.016939,-.013695,
-.016759,-.014368,
-.016464,-.015,
-.016064,-.015571,
-.015571,-.016064,
-.015,-.016464,
-.014368,-.016759,
-.013695,-.016939,
-.013,-.017,
.013,-.017,
.013695,-.016939,
.014368,-.016759,
.015,-.016464,
.015571,-.016064,
.016064,-.015571,
.016464,-.015,
.016759,-.014368,
.016939,-.013695,
.017,-.013,
0.0*
%
%ADD41MACRO41*%
%AMMACRO25*
4,1,40,.013,.017,
-.013,.017,
-.013695,.016939,
-.014368,.016759,
-.015,.016464,
-.015571,.016064,
-.016064,.015571,
-.016464,.015,
-.016759,.014368,
-.016939,.013695,
-.017,.013,
-.017,-.013,
-.016939,-.013695,
-.016759,-.014368,
-.016464,-.015,
-.016064,-.015571,
-.015571,-.016064,
-.015,-.016464,
-.014368,-.016759,
-.013695,-.016939,
-.013,-.017,
.013,-.017,
.013695,-.016939,
.014368,-.016759,
.015,-.016464,
.015571,-.016064,
.016064,-.015571,
.016464,-.015,
.016759,-.014368,
.016939,-.013695,
.017,-.013,
.017,.013,
.016939,.013695,
.016759,.014368,
.016464,.015,
.016064,.015571,
.015571,.016064,
.015,.016464,
.014368,.016759,
.013695,.016939,
.013,.017,
0.0*
%
%ADD25MACRO25*%
%AMMACRO32*
4,1,40,-.008,-.012,
.008,-.012,
.008695,-.011939,
.009368,-.011759,
.01,-.011464,
.010571,-.011064,
.011064,-.010571,
.011464,-.01,
.011759,-.009368,
.011939,-.008695,
.012,-.008,
.012,.008,
.011939,.008695,
.011759,.009368,
.011464,.01,
.011064,.010571,
.010571,.011064,
.01,.011464,
.009368,.011759,
.008695,.011939,
.008,.012,
-.008,.012,
-.008695,.011939,
-.009368,.011759,
-.01,.011464,
-.010571,.011064,
-.011064,.010571,
-.011464,.01,
-.011759,.009368,
-.011939,.008695,
-.012,.008,
-.012,-.008,
-.011939,-.008695,
-.011759,-.009368,
-.011464,-.01,
-.011064,-.010571,
-.010571,-.011064,
-.01,-.011464,
-.009368,-.011759,
-.008695,-.011939,
-.008,-.012,
0.0*
%
%ADD32MACRO32*%
%AMMACRO31*
4,1,40,.012,-.008,
.012,.008,
.011939,.008695,
.011759,.009368,
.011464,.01,
.011064,.010571,
.010571,.011064,
.01,.011464,
.009368,.011759,
.008695,.011939,
.008,.012,
-.008,.012,
-.008695,.011939,
-.009368,.011759,
-.01,.011464,
-.010571,.011064,
-.011064,.010571,
-.011464,.01,
-.011759,.009368,
-.011939,.008695,
-.012,.008,
-.012,-.008,
-.011939,-.008695,
-.011759,-.009368,
-.011464,-.01,
-.011064,-.010571,
-.010571,-.011064,
-.01,-.011464,
-.009368,-.011759,
-.008695,-.011939,
-.008,-.012,
.008,-.012,
.008695,-.011939,
.009368,-.011759,
.01,-.011464,
.010571,-.011064,
.011064,-.010571,
.011464,-.01,
.011759,-.009368,
.011939,-.008695,
.012,-.008,
0.0*
%
%ADD31MACRO31*%
%AMMACRO16*
4,1,40,-.007,-.011,
.007,-.011,
.007695,-.010939,
.008368,-.010759,
.009,-.010464,
.009571,-.010064,
.010064,-.009571,
.010464,-.009,
.010759,-.008368,
.010939,-.007695,
.011,-.007,
.011,.007,
.010939,.007695,
.010759,.008368,
.010464,.009,
.010064,.009571,
.009571,.010064,
.009,.010464,
.008368,.010759,
.007695,.010939,
.007,.011,
-.007,.011,
-.007695,.010939,
-.008368,.010759,
-.009,.010464,
-.009571,.010064,
-.010064,.009571,
-.010464,.009,
-.010759,.008368,
-.010939,.007695,
-.011,.007,
-.011,-.007,
-.010939,-.007695,
-.010759,-.008368,
-.010464,-.009,
-.010064,-.009571,
-.009571,-.010064,
-.009,-.010464,
-.008368,-.010759,
-.007695,-.010939,
-.007,-.011,
0.0*
%
%ADD16MACRO16*%
%AMMACRO14*
4,1,40,-.011,.007,
-.011,-.007,
-.010939,-.007695,
-.010759,-.008368,
-.010464,-.009,
-.010064,-.009571,
-.009571,-.010064,
-.009,-.010464,
-.008368,-.010759,
-.007695,-.010939,
-.007,-.011,
.007,-.011,
.007695,-.010939,
.008368,-.010759,
.009,-.010464,
.009571,-.010064,
.010064,-.009571,
.010464,-.009,
.010759,-.008368,
.010939,-.007695,
.011,-.007,
.011,.007,
.010939,.007695,
.010759,.008368,
.010464,.009,
.010064,.009571,
.009571,.010064,
.009,.010464,
.008368,.010759,
.007695,.010939,
.007,.011,
-.007,.011,
-.007695,.010939,
-.008368,.010759,
-.009,.010464,
-.009571,.010064,
-.010064,.009571,
-.010464,.009,
-.010759,.008368,
-.010939,.007695,
-.011,.007,
0.0*
%
%ADD14MACRO14*%
%ADD78C,.006*%
G75*
%LPD*%
G75*
G36*
G01X141510Y193899D02*
Y183799D01*
X152810D01*
Y193899D01*
X141510D01*
G37*
G36*
G01Y206599D02*
Y196499D01*
X152810D01*
Y206599D01*
X141510D01*
G37*
G36*
G01X78701Y791458D02*
X100293D01*
Y801694D01*
X78701D01*
Y791458D01*
G37*
G36*
G01Y804292D02*
X95237D01*
Y812899D01*
X78701D01*
Y804292D01*
G37*
G36*
G01Y815499D02*
X95237D01*
Y824106D01*
X78701D01*
Y815499D01*
G37*
G36*
G01Y826706D02*
X95237D01*
Y835313D01*
X78701D01*
Y826706D01*
G37*
G36*
G01X118518Y801694D02*
X140543D01*
Y799712D01*
G03X149143I4300J-933D01*
G01Y801694D01*
X159343D01*
Y791458D01*
X118518D01*
Y801694D01*
G37*
G36*
G01X78701Y837913D02*
X95237D01*
Y846520D01*
X78701D01*
Y837913D01*
G37*
G36*
G01Y849120D02*
X95237D01*
Y857727D01*
X78701D01*
Y849120D01*
G37*
G36*
G01Y860327D02*
X95237D01*
Y868934D01*
X78701D01*
Y860327D01*
G37*
G36*
G01Y871534D02*
X100293D01*
Y881770D01*
X78701D01*
Y871534D01*
G37*
G36*
G01X118518Y881770D02*
X159368D01*
Y871534D01*
X149143D01*
Y873516D01*
G03X140543I-4300J933D01*
G01Y871534D01*
X118518D01*
Y881770D01*
G37*
G36*
G01X155410Y193899D02*
Y183799D01*
X166710D01*
Y193899D01*
X155410D01*
G37*
G36*
G01Y206599D02*
Y196499D01*
X166710D01*
Y206599D01*
X155410D01*
G37*
G36*
G01X221108Y157068D02*
Y152068D01*
X213108D01*
Y157068D01*
X221108D01*
G37*
G36*
G01X177593Y801694D02*
X190393D01*
Y820276D01*
X198701D01*
Y791458D01*
X177593D01*
Y801694D01*
G37*
G36*
G01X177568Y871534D02*
X190393D01*
Y854526D01*
X198701D01*
Y881770D01*
X177568D01*
Y871534D01*
G37*
G36*
G01X243608Y161568D02*
Y147568D01*
X235608D01*
Y161568D01*
X243608D01*
G37*
G54D10*
X-1011811Y-15748D03*
Y940945D03*
X775591Y-15748D03*
Y940944D03*
G54D20*
X63000Y99900D03*
X67300D03*
X50963Y378983D03*
X46763Y394483D03*
X50830Y394489D03*
X50963Y386783D03*
X46763Y387083D03*
X61563Y370883D03*
X60122Y751061D03*
X107783Y83161D03*
X91178Y207933D03*
X80326Y655588D03*
X79967Y640094D03*
X80653Y755247D03*
X80415Y772933D03*
X208612Y78030D03*
X219504Y178170D03*
X177087Y172033D03*
X185215Y414633D03*
X185266Y489643D03*
X219303Y744714D03*
X229613Y61498D03*
X223817Y178208D03*
X235414Y214313D03*
X238000Y414700D03*
X227900Y414600D03*
X232100D03*
X240662Y383684D03*
X241728Y356756D03*
X237455Y367855D03*
X242700Y436600D03*
X223658Y744714D03*
X234524Y771383D03*
X447090Y500442D03*
X504027Y409475D03*
X504094Y401932D03*
X503981Y417019D03*
X525463Y542533D03*
X665909Y462723D03*
X649409Y479323D03*
X670009Y458623D03*
X653509Y475023D03*
X711409Y450523D03*
X650700Y529500D03*
X689190Y768106D03*
X715509Y454523D03*
X732109Y471123D03*
X727909Y466823D03*
G54D11*
X-944882Y-17185D03*
Y942382D03*
X43000Y354200D03*
X245200Y551000D03*
X708683Y-17218D03*
G54D21*
X70675Y134665D03*
X54925D03*
X70675Y155935D03*
X54925D03*
G54D30*
X33253Y486907D03*
X25653D03*
X33250Y479024D03*
X25650D03*
X245837Y83579D03*
X253437D03*
X302287Y456235D03*
X294687D03*
X653800Y520900D03*
X646200D03*
X653819Y513168D03*
X646219D03*
G54D12*
X58059Y84803D03*
Y86768D03*
Y88738D03*
Y90708D03*
Y92673D03*
X74359D03*
Y90708D03*
Y88738D03*
Y86768D03*
Y84803D03*
X107899Y197156D03*
Y195191D03*
Y193221D03*
Y191251D03*
Y189286D03*
X91599D03*
Y191251D03*
Y193221D03*
Y195191D03*
Y197156D03*
X82163Y244428D03*
Y246398D03*
Y248368D03*
Y250338D03*
Y252308D03*
Y254278D03*
Y256248D03*
Y258218D03*
Y260188D03*
Y262158D03*
Y264128D03*
Y266098D03*
Y268068D03*
Y270038D03*
Y272008D03*
Y273978D03*
Y275948D03*
Y277918D03*
Y279888D03*
Y281858D03*
Y283828D03*
Y285798D03*
Y287768D03*
Y289738D03*
X157763Y273978D03*
Y272008D03*
Y270038D03*
Y268068D03*
Y266098D03*
Y264128D03*
Y262158D03*
Y260188D03*
Y258218D03*
Y256248D03*
Y254278D03*
Y252308D03*
Y250338D03*
Y248368D03*
Y246398D03*
Y244428D03*
Y289738D03*
Y287768D03*
Y285798D03*
Y283828D03*
Y281858D03*
Y279888D03*
Y277918D03*
Y275948D03*
X476320Y508067D03*
Y506102D03*
Y504132D03*
Y502162D03*
Y500197D03*
X460020D03*
Y502162D03*
Y504132D03*
Y506102D03*
Y508067D03*
G54D31*
X27990Y497166D03*
X80800Y199800D03*
X99041Y203600D03*
X219061Y461171D03*
X219034Y464704D03*
X233200Y454700D03*
X298500Y466600D03*
X478728Y493916D03*
X460520Y493874D03*
G54D13*
X43100Y103500D03*
X46863Y378983D03*
X65763Y370883D03*
X59384Y637701D03*
X84296Y192448D03*
X149031Y168900D03*
X115096Y186970D03*
X79922Y632686D03*
X80191Y647887D03*
X80653Y747704D03*
X80464Y764806D03*
X217113Y130860D03*
X172685Y172033D03*
X168353Y140290D03*
X189415Y413533D03*
X185266Y481943D03*
X225231Y61620D03*
X225002Y130816D03*
X231350Y214208D03*
X226428Y395041D03*
X222254Y394949D03*
X236637Y383693D03*
X241728Y364256D03*
X237455Y375355D03*
X246800Y436600D03*
X231108Y464137D03*
X226992Y464083D03*
X537200Y394400D03*
X657609Y470923D03*
X661709Y466823D03*
X674109Y454523D03*
X678509Y450323D03*
X654800Y529500D03*
X736209Y475223D03*
X740309Y479423D03*
X723809Y462723D03*
X719709Y458623D03*
G54D22*
X77200Y199800D03*
X24390Y497166D03*
X95441Y203600D03*
X215461Y461171D03*
X215434Y464704D03*
X229600Y454700D03*
X294900Y466600D03*
X475128Y493916D03*
X456920Y493874D03*
G54D40*
X59800Y764900D03*
X93130Y145135D03*
X212000Y171900D03*
X201547Y407074D03*
X207141Y386759D03*
X185614Y458881D03*
X215006Y438401D03*
X190714Y458681D03*
X247262Y519409D03*
G54D14*
X43100Y106900D03*
X46863Y382383D03*
X65763Y374283D03*
X59384Y641101D03*
X84296Y195848D03*
X149031Y172300D03*
X115096Y190370D03*
X79922Y636086D03*
X80191Y651287D03*
X80653Y751104D03*
X80464Y768206D03*
X217113Y134260D03*
X172685Y175433D03*
X168353Y143690D03*
X185266Y485343D03*
X189415Y416933D03*
X225231Y65020D03*
X225002Y134216D03*
X231350Y217608D03*
X226428Y398441D03*
X222254Y398349D03*
X236637Y387093D03*
X241728Y367656D03*
X237455Y378755D03*
X246800Y440000D03*
X231108Y467537D03*
X226992Y467483D03*
X537200Y397800D03*
X657609Y474323D03*
X661709Y470223D03*
X674109Y457923D03*
X678509Y453723D03*
X654800Y532900D03*
X736209Y478623D03*
X740309Y482823D03*
X723809Y466123D03*
X719709Y462023D03*
G54D32*
X77453Y525824D03*
X69970Y521539D03*
X66497Y521555D03*
X59007Y525728D03*
X55470Y525648D03*
X47790Y521300D03*
X44031Y521396D03*
X136663Y521903D03*
X133163Y522003D03*
X147678Y526068D03*
X144206Y526034D03*
X125501Y526046D03*
X122044Y526062D03*
X114546Y521952D03*
X110786Y521951D03*
X103330Y525965D03*
X99797Y525846D03*
X92158Y521634D03*
X88606Y521633D03*
X81117Y525760D03*
X204811Y77927D03*
X153061Y168712D03*
X219655Y214498D03*
X200498Y388564D03*
X205667Y406683D03*
X214163Y526003D03*
X210563Y526103D03*
X202963Y521903D03*
X199363D03*
X191863Y526203D03*
X188363D03*
X180845Y521911D03*
X177324Y521927D03*
X169812Y526147D03*
X166180Y526146D03*
X158691Y521893D03*
X155181Y521942D03*
X258530Y81926D03*
X243200Y520700D03*
X277254Y845565D03*
X337612Y430423D03*
X341344D03*
X360415D03*
X356714D03*
X352814D03*
X348914D03*
X345014D03*
X387100D03*
X383102D03*
X371187D03*
X367432D03*
X363968D03*
X379184D03*
X375464D03*
G54D41*
X59800Y770500D03*
X93130Y150735D03*
X212000Y177500D03*
X201547Y412674D03*
X207141Y392359D03*
X185614Y464481D03*
X215006Y444001D03*
X190714Y464281D03*
X247262Y525009D03*
G54D23*
X43760Y172352D03*
X69800Y180800D03*
X103041Y203500D03*
X115041Y202800D03*
X144600Y233900D03*
X214190Y98033D03*
X199561Y113456D03*
X189163Y240983D03*
X189121Y244556D03*
X189163Y248183D03*
Y237383D03*
X185309Y421839D03*
X189466Y493343D03*
X249782Y399333D03*
X249041Y383206D03*
X241555Y375055D03*
X241530Y371576D03*
X245865Y363969D03*
X245828Y360456D03*
X237500Y454700D03*
X223399Y778667D03*
X487203Y501502D03*
X487218Y494161D03*
X487223Y497927D03*
X515916Y424009D03*
X517452Y552477D03*
X517613Y548807D03*
X693339Y759399D03*
X693392Y762972D03*
X694427Y817304D03*
X694375Y820842D03*
G54D50*
X140847Y223231D03*
X162963D03*
G54D15*
X48500Y93600D03*
X66863Y267083D03*
X59263D03*
X66363Y272683D03*
X66863Y258783D03*
X59263Y258883D03*
X66863Y254683D03*
X59263Y251483D03*
X67063Y250483D03*
Y246283D03*
X59146Y242114D03*
X66963Y242083D03*
X67063Y237683D03*
X66863Y262883D03*
X66801Y294778D03*
Y290678D03*
X58863Y285083D03*
X66496Y285730D03*
Y281630D03*
X58863Y276783D03*
X66363D03*
X50680Y373862D03*
X66222Y517540D03*
X55179Y521570D03*
X43855Y517250D03*
X77242Y521666D03*
X91241Y203800D03*
X118571Y206661D03*
X143553Y331742D03*
X132417Y335856D03*
X120955Y331729D03*
X132863Y517903D03*
X88362Y517603D03*
X99385Y521826D03*
X110607Y517857D03*
X121751Y522079D03*
X143912Y522038D03*
X206425Y98053D03*
X154552Y335814D03*
X176638Y344153D03*
X165585Y339913D03*
X209880Y356594D03*
X198838Y352449D03*
X187757Y348289D03*
X192966Y481243D03*
X177049Y517848D03*
X154874Y517879D03*
X165905Y522020D03*
X210263Y522003D03*
X199063Y517803D03*
X188063Y522003D03*
X221359Y106010D03*
X250115Y93933D03*
X250090Y89833D03*
X248046Y77735D03*
X248190Y102533D03*
X248052Y73668D03*
X227102Y214585D03*
X252553Y387029D03*
X221085Y363914D03*
X246097Y432409D03*
X238700Y482954D03*
X234562Y779010D03*
X234666Y783159D03*
X234621Y787335D03*
X285742Y794780D03*
X338146Y793055D03*
X353927Y792923D03*
X308899Y794862D03*
X319115Y795010D03*
X297576Y794808D03*
X490830Y532955D03*
X490838Y541335D03*
X490523Y549911D03*
X478687Y490049D03*
X460541Y490002D03*
X490899Y508498D03*
X490902Y512828D03*
X450818Y508324D03*
X508100Y389700D03*
X511734Y424179D03*
X528810Y531644D03*
X528788Y527470D03*
X711409Y453923D03*
X661009Y474323D03*
X665109Y470223D03*
X677509Y457923D03*
X681909Y453723D03*
X692400Y537000D03*
X732109Y474523D03*
X727909Y470223D03*
X715509Y458023D03*
X729191Y857331D03*
G54D33*
X77453Y529424D03*
X69970Y525139D03*
X66497Y525155D03*
X59007Y529328D03*
X55470Y529248D03*
X47790Y524900D03*
X44031Y524996D03*
X136663Y525503D03*
X133163Y525603D03*
X147678Y529668D03*
X144206Y529634D03*
X125501Y529646D03*
X122044Y529662D03*
X114546Y525552D03*
X110786Y525551D03*
X103330Y529565D03*
X99797Y529446D03*
X92158Y525234D03*
X88606Y525233D03*
X81117Y529360D03*
X204811Y81527D03*
X153061Y172312D03*
X219655Y218098D03*
X200498Y392164D03*
X205667Y410283D03*
X214163Y529603D03*
X210563Y529703D03*
X202963Y525503D03*
X199363D03*
X191863Y529803D03*
X188363D03*
X180845Y525511D03*
X177324Y525527D03*
X169812Y529747D03*
X166180Y529746D03*
X158691Y525493D03*
X155181Y525542D03*
X258530Y85526D03*
X243200Y524300D03*
X277254Y849165D03*
X337612Y434023D03*
X341344D03*
X360415D03*
X356714D03*
X352814D03*
X348914D03*
X345014D03*
X387100D03*
X383102D03*
X371187D03*
X367432D03*
X363968D03*
X379184D03*
X375464D03*
G54D60*
X217108Y145568D03*
Y163568D03*
G54D51*
X147553Y327542D03*
X143853Y327642D03*
X136317Y331756D03*
X132717D03*
X124973Y327655D03*
X121255Y327729D03*
X201315Y81433D03*
X154641Y154448D03*
X191557Y344189D03*
X188047Y344249D03*
X180438Y340053D03*
X176898Y340013D03*
X169385Y335813D03*
X165885D03*
X158445Y331748D03*
X154845Y331848D03*
X185315Y410533D03*
X213780Y352494D03*
X210180D03*
X202638Y348349D03*
X199138D03*
X206788Y420845D03*
X207834Y465396D03*
X221100Y134300D03*
X249515Y394680D03*
X224885Y359814D03*
X221424Y359867D03*
X256700Y489500D03*
X260200D03*
X353898Y467743D03*
X349945Y467753D03*
X358012Y467743D03*
X345813D03*
X394125Y398023D03*
X390405D03*
X383048D03*
X379164D03*
X397699D03*
X386726D03*
X375610D03*
X365427Y467743D03*
X361642D03*
X451123Y503983D03*
X504316Y397727D03*
X664700Y543300D03*
G54D24*
X47360Y172352D03*
X73400Y180800D03*
X106641Y203500D03*
X118641Y202800D03*
X148200Y233900D03*
X217790Y98033D03*
X203161Y113456D03*
X192763Y240983D03*
X192721Y244556D03*
X192763Y248183D03*
Y237383D03*
X188909Y421839D03*
X193066Y493343D03*
X253382Y399333D03*
X252641Y383206D03*
X245155Y375055D03*
X245130Y371576D03*
X249465Y363969D03*
X249428Y360456D03*
X241100Y454700D03*
X226999Y778667D03*
X490803Y501502D03*
X490818Y494161D03*
X490823Y497927D03*
X519516Y424009D03*
X521052Y552477D03*
X521213Y548807D03*
X696939Y759399D03*
X696992Y762972D03*
X698027Y817304D03*
X697975Y820842D03*
G54D42*
X151400Y54700D03*
X116689Y54714D03*
X103528D03*
X151400Y66300D03*
X116689Y66314D03*
X103528D03*
X164500Y54700D03*
Y66300D03*
G54D16*
X45100Y93600D03*
X63463Y267083D03*
X55863D03*
X62963Y272683D03*
X63463Y258783D03*
X55863Y258883D03*
X63463Y254683D03*
X55863Y251483D03*
X63663Y250483D03*
Y246283D03*
X55746Y242114D03*
X63563Y242083D03*
X63663Y237683D03*
X63463Y262883D03*
X63401Y294778D03*
Y290678D03*
X55463Y285083D03*
X63096Y285730D03*
Y281630D03*
X55463Y276783D03*
X62963D03*
X47280Y373862D03*
X62822Y517540D03*
X51779Y521570D03*
X40455Y517250D03*
X73842Y521666D03*
X87841Y203800D03*
X115171Y206661D03*
X140153Y331742D03*
X129017Y335856D03*
X117555Y331729D03*
X129463Y517903D03*
X84962Y517603D03*
X95985Y521826D03*
X107207Y517857D03*
X118351Y522079D03*
X140512Y522038D03*
X217959Y106010D03*
X203025Y98053D03*
X151152Y335814D03*
X173238Y344153D03*
X162185Y339913D03*
X206480Y356594D03*
X217685Y363914D03*
X195438Y352449D03*
X184357Y348289D03*
X189566Y481243D03*
X173649Y517848D03*
X151474Y517879D03*
X162505Y522020D03*
X206863Y522003D03*
X195663Y517803D03*
X184663Y522003D03*
X246715Y93933D03*
X246690Y89833D03*
X244646Y77735D03*
X244790Y102533D03*
X244652Y73668D03*
X223702Y214585D03*
X249153Y387029D03*
X242697Y432409D03*
X235300Y482954D03*
X231162Y779010D03*
X231266Y783159D03*
X231221Y787335D03*
X282342Y794780D03*
X334746Y793055D03*
X350527Y792923D03*
X305499Y794862D03*
X315715Y795010D03*
X294176Y794808D03*
X487430Y532955D03*
X487438Y541335D03*
X487123Y549911D03*
X475287Y490049D03*
X457141Y490002D03*
X487499Y508498D03*
X487502Y512828D03*
X447418Y508324D03*
X504700Y389700D03*
X508334Y424179D03*
X525410Y531644D03*
X525388Y527470D03*
X708009Y453923D03*
X657609Y474323D03*
X712109Y458023D03*
X661709Y470223D03*
X674109Y457923D03*
X678509Y453723D03*
X689000Y537000D03*
X728709Y474523D03*
X724509Y470223D03*
X725791Y857331D03*
G54D25*
X77688Y184954D03*
X24894Y493063D03*
X149631Y176850D03*
X157313Y171759D03*
X208182Y427789D03*
X211343Y418666D03*
X244700Y461100D03*
X235756Y478217D03*
X236673Y468923D03*
X299174Y475788D03*
X294700Y462500D03*
X299213Y471007D03*
G54D43*
X134000Y52600D03*
Y77400D03*
X281963Y485753D03*
Y510553D03*
X340774Y65179D03*
Y40379D03*
X310274Y65179D03*
Y40379D03*
X343791Y395598D03*
X343292Y485604D03*
X312767Y485379D03*
X343791Y420398D03*
X323221Y445562D03*
Y470362D03*
X343292Y510404D03*
X312767Y510179D03*
X371274Y65179D03*
Y40379D03*
G54D34*
X33845Y507529D03*
Y499929D03*
X41797Y500609D03*
Y508209D03*
X99375Y144069D03*
Y151669D03*
X123397Y144069D03*
Y151669D03*
X115601Y144069D03*
Y151669D03*
X107672Y144069D03*
Y151669D03*
X174950Y133259D03*
X183700Y133300D03*
X183034Y162805D03*
Y170405D03*
X197209Y165797D03*
Y158197D03*
X174950Y140859D03*
X183700Y140900D03*
X205600Y165800D03*
Y158200D03*
X194877Y385099D03*
Y392699D03*
X187165Y385235D03*
Y392835D03*
X195311Y407990D03*
Y415590D03*
X215284Y382027D03*
Y389627D03*
X200959Y429749D03*
Y422149D03*
X197214Y464181D03*
Y456581D03*
X238000Y60400D03*
Y52800D03*
X263100Y60400D03*
Y52800D03*
X254900Y60400D03*
Y52800D03*
X246400Y60400D03*
Y52800D03*
X223321Y389661D03*
Y382061D03*
X254182Y496347D03*
Y503947D03*
X237203Y519878D03*
Y527478D03*
X261424Y519113D03*
Y526713D03*
X253508Y519183D03*
Y526783D03*
X238118Y504116D03*
Y496516D03*
X246132Y504110D03*
Y496510D03*
X262501Y504118D03*
Y496518D03*
X229241Y527601D03*
Y520001D03*
G54D61*
X200788Y473418D03*
X216324D03*
X200788Y493918D03*
X216324D03*
G54D52*
X147553Y323942D03*
X143853Y324042D03*
X136317Y328156D03*
X132717D03*
X124973Y324055D03*
X121255Y324129D03*
X201315Y77833D03*
X154641Y150848D03*
X202638Y344749D03*
X199138D03*
X191557Y340589D03*
X188047Y340649D03*
X180438Y336453D03*
X176898Y336413D03*
X169385Y332213D03*
X165885D03*
X158445Y328148D03*
X154845Y328248D03*
X185315Y406933D03*
X213780Y348894D03*
X210180D03*
X206788Y417245D03*
X207834Y461796D03*
X221100Y130700D03*
X249515Y391080D03*
X224885Y356214D03*
X221424Y356267D03*
X256700Y485900D03*
X260200D03*
X353898Y464143D03*
X349945Y464153D03*
X358012Y464143D03*
X345813D03*
X394125Y394423D03*
X390405D03*
X383048D03*
X379164D03*
X397699D03*
X386726D03*
X375610D03*
X365427Y464143D03*
X361642D03*
X451123Y500383D03*
X504316Y394127D03*
X664700Y539700D03*
G54D70*
X501750Y380000D03*
X520250D03*
G54D62*
X216324Y483668D03*
X200788D03*
G54D44*
X97645Y134201D03*
X92645D03*
X87645D03*
X82645D03*
Y114201D03*
X87645D03*
X92645D03*
X97645D03*
G54D26*
X73943Y205660D03*
Y213410D03*
X72930Y633923D03*
Y641673D03*
X65430Y637798D03*
X72814Y652628D03*
Y660378D03*
X65314Y656503D03*
X73412Y748676D03*
Y756426D03*
X65912Y752551D03*
X73356Y767193D03*
Y774943D03*
X65856Y771068D03*
X81443Y209535D03*
G54D53*
X216447Y72290D03*
Y74259D03*
Y76227D03*
Y78196D03*
Y80164D03*
Y82133D03*
Y84102D03*
Y86070D03*
Y88039D03*
Y90007D03*
Y91976D03*
X235733D03*
Y90007D03*
Y88039D03*
Y86070D03*
Y84102D03*
Y82133D03*
Y80164D03*
Y78196D03*
Y76227D03*
Y74259D03*
Y72290D03*
G54D71*
X497166Y535119D03*
Y537679D03*
Y540239D03*
Y542799D03*
X519366D03*
Y540239D03*
Y537679D03*
Y535119D03*
X695412Y836919D03*
Y834419D03*
Y831919D03*
Y829419D03*
Y826919D03*
X696098Y796516D03*
Y794016D03*
Y791516D03*
Y789016D03*
Y786516D03*
Y784016D03*
Y781516D03*
Y779016D03*
Y776516D03*
Y774016D03*
Y771516D03*
Y769016D03*
X695412Y854419D03*
Y851919D03*
Y849419D03*
Y846919D03*
Y844419D03*
Y841919D03*
Y839419D03*
X716012Y826919D03*
Y829419D03*
Y831919D03*
Y834419D03*
Y836919D03*
X716698Y769016D03*
Y771516D03*
Y774016D03*
Y776516D03*
Y779016D03*
Y781516D03*
Y784016D03*
Y786516D03*
Y789016D03*
Y791516D03*
Y794016D03*
Y796516D03*
X716012Y839419D03*
Y841919D03*
Y844419D03*
Y846919D03*
Y849419D03*
Y851919D03*
Y854419D03*
G54D17*
X45100Y89400D03*
X45200Y82900D03*
X72569Y219284D03*
X70277Y517540D03*
X59282Y521602D03*
X48002Y517237D03*
X63807Y647187D03*
X64298Y761923D03*
X149282Y164664D03*
X110971Y182699D03*
X84700Y141100D03*
X115141Y199000D03*
X117341Y194500D03*
X147610Y331731D03*
X136517Y335856D03*
X125273Y331655D03*
X136963Y517903D03*
X81425Y521698D03*
X92450Y517603D03*
X103504Y521857D03*
X114725Y517858D03*
X125800Y522071D03*
X147954Y522037D03*
X214222Y101900D03*
X203020Y93789D03*
X201664Y85481D03*
X203290Y102533D03*
X160361Y145062D03*
X159849Y176397D03*
X176482Y271928D03*
X176343Y267018D03*
X177356Y261409D03*
X175709Y256562D03*
X175577Y251228D03*
X175450Y246422D03*
X173990Y237502D03*
Y241702D03*
X176410Y281361D03*
X176443Y276656D03*
X176610Y294061D03*
X176510Y285561D03*
X176610Y289861D03*
X158681Y335850D03*
X180738Y344153D03*
X169685Y339913D03*
X214080Y356594D03*
X202938Y352449D03*
X191857Y348289D03*
X212100Y449700D03*
X189566Y485443D03*
Y489543D03*
X181104Y517848D03*
X158967Y517830D03*
X170087Y522020D03*
X214463Y521903D03*
X203263Y517803D03*
X192163Y522003D03*
X244790Y98033D03*
X223666Y218917D03*
X232758Y405205D03*
X249809Y403106D03*
X225139Y363907D03*
X242703Y428291D03*
X235199Y461252D03*
X235316Y473688D03*
X358000Y792962D03*
X342834Y792836D03*
X458763Y514834D03*
X466395D03*
X487437Y528628D03*
X487483Y537159D03*
X487213Y545645D03*
X487366Y489976D03*
X529300Y393000D03*
X645700Y394600D03*
X670009Y462023D03*
X653509Y478423D03*
X649409Y482723D03*
X665909Y466123D03*
X688300Y544300D03*
X732809Y478623D03*
X736909Y482823D03*
X720409Y466123D03*
X716309Y462023D03*
X747300Y546500D03*
X749500Y555900D03*
Y551800D03*
X749600Y577500D03*
X749530Y569233D03*
X749537Y560714D03*
X749629Y573387D03*
X725800Y853200D03*
G54D35*
X30494Y493063D03*
X83288Y184954D03*
X162913Y171759D03*
X155231Y176850D03*
X213782Y427789D03*
X216943Y418666D03*
X250300Y461100D03*
X241356Y478217D03*
X242273Y468923D03*
X304774Y475788D03*
X300300Y462500D03*
X304813Y471007D03*
G54D27*
X71660Y193550D03*
X69100D03*
X66540D03*
Y187050D03*
X71660D03*
G54D54*
X193000Y130850D03*
Y146350D03*
X274405Y63139D03*
Y47639D03*
G54D63*
X194548Y827952D03*
Y837401D03*
Y846849D03*
G54D72*
X510634Y403425D03*
Y408425D03*
Y413425D03*
X530634D03*
Y408425D03*
Y403425D03*
X510634Y418425D03*
X530634D03*
G54D45*
X151866Y100449D03*
X189416D03*
G54D36*
X75118Y561024D03*
Y564174D03*
Y567323D03*
Y570473D03*
Y573622D03*
Y576772D03*
Y579922D03*
Y583071D03*
Y586221D03*
Y589370D03*
Y592520D03*
Y595670D03*
Y598819D03*
Y601969D03*
Y605118D03*
Y608268D03*
Y611418D03*
Y614567D03*
Y679134D03*
Y682284D03*
Y685433D03*
Y688583D03*
Y691732D03*
Y694882D03*
Y698032D03*
Y701181D03*
Y704331D03*
Y707480D03*
Y710630D03*
Y713780D03*
Y716929D03*
Y720079D03*
Y723228D03*
Y726378D03*
Y729528D03*
Y732677D03*
X85000Y562599D03*
Y565748D03*
Y568898D03*
Y572048D03*
Y575197D03*
Y578347D03*
Y581496D03*
Y584646D03*
Y587796D03*
Y590945D03*
Y594095D03*
Y597244D03*
Y600394D03*
Y603544D03*
Y606693D03*
Y609843D03*
Y612992D03*
Y616142D03*
Y680709D03*
Y683858D03*
Y687008D03*
Y690158D03*
Y693307D03*
Y696457D03*
Y699606D03*
Y702756D03*
Y705906D03*
Y709055D03*
Y712205D03*
Y715354D03*
Y718504D03*
Y721654D03*
Y724803D03*
Y727953D03*
Y731102D03*
Y734252D03*
X175118Y818504D03*
Y821654D03*
Y824804D03*
Y827954D03*
Y831104D03*
Y834254D03*
Y837399D03*
X165238Y816929D03*
Y820079D03*
Y823229D03*
Y826379D03*
Y829529D03*
Y832679D03*
Y835829D03*
X175118Y840549D03*
X165238Y838974D03*
Y842124D03*
X175118Y843699D03*
Y846849D03*
Y849999D03*
Y853149D03*
Y856299D03*
X165238Y845274D03*
Y848424D03*
Y851574D03*
Y854724D03*
G54D18*
X48500Y89400D03*
X48600Y82900D03*
X75969Y219284D03*
X73677Y517540D03*
X62682Y521602D03*
X51402Y517237D03*
X67207Y647187D03*
X67698Y761923D03*
X114371Y182699D03*
X88100Y141100D03*
X118541Y199000D03*
X120741Y194500D03*
X139917Y335856D03*
X128673Y331655D03*
X140363Y517903D03*
X84825Y521698D03*
X95850Y517603D03*
X106904Y521857D03*
X118125Y517858D03*
X129200Y522071D03*
X217622Y101900D03*
X206420Y93789D03*
X205064Y85481D03*
X206690Y102533D03*
X152682Y164664D03*
X163761Y145062D03*
X163249Y176397D03*
X179882Y271928D03*
X179743Y267018D03*
X180756Y261409D03*
X179109Y256562D03*
X178977Y251228D03*
X178850Y246422D03*
X177390Y237502D03*
Y241702D03*
X179810Y281361D03*
X179843Y276656D03*
X180010Y294061D03*
X179910Y285561D03*
X180010Y289861D03*
X162081Y335850D03*
X151010Y331731D03*
X184138Y344153D03*
X173085Y339913D03*
X217480Y356594D03*
X206338Y352449D03*
X195257Y348289D03*
X215500Y449700D03*
X192966Y485443D03*
Y489543D03*
X184504Y517848D03*
X151354Y522037D03*
X162367Y517830D03*
X173487Y522020D03*
X217863Y521903D03*
X206663Y517803D03*
X195563Y522003D03*
X248190Y98033D03*
X227066Y218917D03*
X236158Y405205D03*
X253209Y403106D03*
X228539Y363907D03*
X246103Y428291D03*
X238599Y461252D03*
X238716Y473688D03*
X346234Y792836D03*
X361400Y792962D03*
X462163Y514834D03*
X469795D03*
X490837Y528628D03*
X490883Y537159D03*
X490613Y545645D03*
X490766Y489976D03*
X532700Y393000D03*
X649100Y394600D03*
X673409Y462023D03*
X656909Y478423D03*
X652809Y482723D03*
X669309Y466123D03*
X691700Y544300D03*
X736209Y478623D03*
X740309Y482823D03*
X723809Y466123D03*
X719709Y462023D03*
X750700Y546500D03*
X752900Y555900D03*
Y551800D03*
X753000Y577500D03*
X752930Y569233D03*
X752937Y560714D03*
X753029Y573387D03*
X729200Y853200D03*
G54D73*
X513500Y396160D03*
Y393600D03*
Y391040D03*
X520900D03*
Y393600D03*
Y396160D03*
G54D55*
X166649Y132647D03*
G54D64*
X226090Y82133D03*
G54D37*
X68140Y665912D03*
X104541Y207700D03*
X250667Y69296D03*
X277770Y794774D03*
X532500Y397400D03*
G54D19*
X63000Y103300D03*
X67300D03*
X50963Y382383D03*
X46763Y397883D03*
X50830Y397889D03*
X50963Y390183D03*
X46763Y390483D03*
X61563Y374283D03*
X60122Y754461D03*
X107783Y86561D03*
X91178Y211333D03*
X80326Y658988D03*
X79967Y643494D03*
X80653Y758647D03*
X80415Y776333D03*
X208612Y81430D03*
X219504Y181570D03*
X177087Y175433D03*
X185215Y418033D03*
X185266Y493043D03*
X219303Y748114D03*
X229613Y64898D03*
X223817Y181608D03*
X235414Y217713D03*
X240662Y387084D03*
X241728Y360156D03*
X237455Y371255D03*
X238000Y418100D03*
X227900Y418000D03*
X242700Y440000D03*
X232100Y418000D03*
X223658Y748114D03*
X234524Y774783D03*
X447090Y503842D03*
X504027Y412875D03*
X504094Y405332D03*
X503981Y420419D03*
X525463Y545933D03*
X665909Y466123D03*
X649409Y482723D03*
X670009Y462023D03*
X653509Y478423D03*
X711409Y453923D03*
X650700Y532900D03*
X689190Y771506D03*
X715509Y457923D03*
X732109Y474523D03*
X727909Y470223D03*
G54D46*
X139878Y135201D03*
Y150469D03*
G54D28*
G01X-771361Y-182763D02*
Y-262763D01*
G01Y-218263D02*
X373639D01*
G01X-771361Y-262763D02*
X373639D01*
G01X-775361Y-166763D02*
G02I-12000J0D01*
G01X-780511D02*
G02I-6850J0D01*
G01X-787361Y-182763D02*
Y-150763D01*
G01X-771361Y-166763D02*
X-803361D01*
G01X-771361Y-182763D02*
X373639D01*
G01X-413861D02*
Y-262763D01*
G01X-276361Y-182763D02*
Y-262763D01*
G01X-161361Y-182763D02*
Y-262763D01*
G01X6139Y-182763D02*
Y-262763D01*
G01X176139Y-182763D02*
Y-262763D01*
G01X373639Y-182763D02*
Y-262763D01*
G01X401639Y-166763D02*
G02I-12000J0D01*
G01X396489D02*
G02I-6850J0D01*
G01X389639Y-182763D02*
Y-150763D01*
G01X405639Y-166763D02*
X373639D01*
X72838Y388509D03*
X68901D03*
X72838Y392446D03*
X68901D03*
X64964D03*
X72838Y396383D03*
X68901D03*
X64964D03*
X68901Y486935D03*
Y494809D03*
X72838D03*
X64964Y490872D03*
X68901D03*
X72838D03*
X64964Y486935D03*
X72838D03*
X167327Y388509D03*
X163390D03*
X171264Y392446D03*
X167327D03*
X163390D03*
X171264Y396383D03*
X167327D03*
X163390D03*
X171264Y486935D03*
X167327D03*
X163390D03*
X171264Y490872D03*
X167327D03*
X163390D03*
X167327Y494809D03*
X163390D03*
G54D74*
X672257Y523769D03*
G54D47*
X129310Y186223D03*
Y204175D03*
G54D56*
X164396Y151107D03*
Y165087D03*
X170302D03*
Y151107D03*
G54D65*
X246455Y107057D03*
G54D38*
X62540Y665912D03*
X98941Y207700D03*
X245067Y69296D03*
X272170Y794774D03*
X526900Y397400D03*
G54D29*
X64964Y416068D03*
X68901D03*
X72838D03*
X76775D03*
X64964Y412131D03*
X68901D03*
X72838D03*
X76775D03*
X64964Y408194D03*
X68901D03*
X72838D03*
X76775D03*
X64964Y404257D03*
X68901D03*
X72838D03*
X76775D03*
X64964Y400320D03*
X68901D03*
X72838D03*
X76775D03*
Y396383D03*
Y392446D03*
Y388509D03*
X64964Y482998D03*
X68901D03*
X72838D03*
X76775D03*
X64964Y479061D03*
X68901D03*
X72838D03*
X76775D03*
X64964Y475124D03*
X68901D03*
X72838D03*
X76775D03*
X64964Y471187D03*
X68901D03*
X72838D03*
X76775D03*
X64964Y467250D03*
X68901D03*
X72838D03*
X76775D03*
X64964Y463313D03*
X68901D03*
X72838D03*
X76775D03*
X64964Y459376D03*
X68901D03*
X72838D03*
X76775D03*
X64964Y455439D03*
X68901D03*
X72838D03*
X76775D03*
X64964Y451502D03*
X68901D03*
X72838D03*
X76775D03*
X64964Y447565D03*
X68901D03*
X72838D03*
X76775D03*
X64964Y443628D03*
X68901D03*
X72838D03*
X76775D03*
X64964Y439690D03*
X68901D03*
X72838D03*
X76775D03*
X64964Y435753D03*
X68901D03*
X72838D03*
X76775D03*
X64964Y431816D03*
X68901D03*
X72838D03*
X76775D03*
X64964Y427879D03*
X68901D03*
X72838D03*
X76775D03*
X64964Y423942D03*
X68901D03*
X72838D03*
X76775D03*
X64964Y420005D03*
X68901D03*
X72838D03*
X76775D03*
Y494809D03*
Y490872D03*
Y486935D03*
X80712Y416068D03*
X84649D03*
X88586D03*
X92523D03*
X96460D03*
X100397D03*
X104334D03*
X108271D03*
X112208D03*
X116145D03*
X120083D03*
X124020D03*
X127957D03*
X131894D03*
X135831D03*
X139768D03*
X143705D03*
X147642D03*
X80712Y412131D03*
X84649D03*
X88586D03*
X92523D03*
X96460D03*
X100397D03*
X104334D03*
X108271D03*
X112208D03*
X116145D03*
X120083D03*
X124020D03*
X127957D03*
X131894D03*
X135831D03*
X139768D03*
X143705D03*
X147642D03*
X80712Y408194D03*
X84649D03*
X88586D03*
X92523D03*
X96460D03*
X100397D03*
X104334D03*
X108271D03*
X112208D03*
X116145D03*
X120083D03*
X124020D03*
X127957D03*
X131894D03*
X135831D03*
X139768D03*
X143705D03*
X147642D03*
X80712Y404257D03*
X84649D03*
X88586D03*
X92523D03*
X96460D03*
X100397D03*
X104334D03*
X108271D03*
X112208D03*
X116145D03*
X120083D03*
X124020D03*
X127957D03*
X131894D03*
X135831D03*
X139768D03*
X143705D03*
X147642D03*
X80712Y400320D03*
X84649D03*
X88586D03*
X92523D03*
X96460D03*
X100397D03*
X104334D03*
X108271D03*
X112208D03*
X116145D03*
X120083D03*
X124020D03*
X127957D03*
X131894D03*
X135831D03*
X139768D03*
X143705D03*
X147642D03*
X80712Y396383D03*
X84649D03*
X88586D03*
X92523D03*
X96460D03*
X100397D03*
X104334D03*
X108271D03*
X112208D03*
X116145D03*
X120083D03*
X124020D03*
X127957D03*
X131894D03*
X135831D03*
X139768D03*
X143705D03*
X147642D03*
X80712Y392446D03*
X84649D03*
X88586D03*
X92523D03*
X96460D03*
X100397D03*
X104334D03*
X108271D03*
X112208D03*
X116145D03*
X120083D03*
X124020D03*
X127957D03*
X131894D03*
X135831D03*
X139768D03*
X143705D03*
X147642D03*
X80712Y388509D03*
X84649D03*
X88586D03*
X92523D03*
X96460D03*
X100397D03*
X104334D03*
X108271D03*
X112208D03*
X116145D03*
X120083D03*
X124020D03*
X127957D03*
X131894D03*
X135831D03*
X139768D03*
X143705D03*
X147642D03*
X80712Y482998D03*
X84649D03*
X88586D03*
X92523D03*
X96460D03*
X100397D03*
X104334D03*
X108271D03*
X112208D03*
X116145D03*
X120083D03*
X124020D03*
X127957D03*
X131894D03*
X135831D03*
X139768D03*
X143705D03*
X147642D03*
X80712Y479061D03*
X84649D03*
X88586D03*
X92523D03*
X96460D03*
X100397D03*
X104334D03*
X108271D03*
X112208D03*
X116145D03*
X120083D03*
X124020D03*
X127957D03*
X131894D03*
X135831D03*
X139768D03*
X143705D03*
X147642D03*
X80712Y475124D03*
X84649D03*
X88586D03*
X92523D03*
X96460D03*
X100397D03*
X104334D03*
X108271D03*
X112208D03*
X116145D03*
X120083D03*
X124020D03*
X127957D03*
X131894D03*
X135831D03*
X139768D03*
X143705D03*
X147642D03*
X80712Y471187D03*
X84649D03*
X88586D03*
X92523D03*
X96460D03*
X100397D03*
X104334D03*
X108271D03*
X112208D03*
X116145D03*
X120083D03*
X124020D03*
X127957D03*
X131894D03*
X135831D03*
X139768D03*
X143705D03*
X147642D03*
X80712Y467250D03*
X84649D03*
X88586D03*
X92523D03*
X96460D03*
X100397D03*
X104334D03*
X108271D03*
X112208D03*
X116145D03*
X120083D03*
X124020D03*
X127957D03*
X131894D03*
X135831D03*
X139768D03*
X143705D03*
X147642D03*
X80712Y463313D03*
X84649D03*
X88586D03*
X92523D03*
X96460D03*
X100397D03*
X104334D03*
X108271D03*
X112208D03*
X116145D03*
X120083D03*
X124020D03*
X127957D03*
X131894D03*
X135831D03*
X139768D03*
X143705D03*
X147642D03*
X80712Y459376D03*
X84649D03*
X88586D03*
X92523D03*
X96460D03*
X100397D03*
X104334D03*
X108271D03*
X112208D03*
X116145D03*
X120083D03*
X124020D03*
X127957D03*
X131894D03*
X135831D03*
X139768D03*
X143705D03*
X147642D03*
X80712Y455439D03*
X84649D03*
X88586D03*
X92523D03*
X96460D03*
X100397D03*
X104334D03*
X108271D03*
X112208D03*
X116145D03*
X120083D03*
X124020D03*
X127957D03*
X131894D03*
X135831D03*
X139768D03*
X143705D03*
X147642D03*
X80712Y451502D03*
X84649D03*
X88586D03*
X92523D03*
X96460D03*
X100397D03*
X104334D03*
X108271D03*
X112208D03*
X116145D03*
X120083D03*
X124020D03*
X127957D03*
X131894D03*
X135831D03*
X139768D03*
X143705D03*
X147642D03*
X80712Y447565D03*
X84649D03*
X88586D03*
X92523D03*
X96460D03*
X100397D03*
X104334D03*
X108271D03*
X112208D03*
X116145D03*
X120083D03*
X124020D03*
X127957D03*
X131894D03*
X135831D03*
X139768D03*
X143705D03*
X147642D03*
X80712Y443628D03*
X84649D03*
X88586D03*
X92523D03*
X96460D03*
X100397D03*
X104334D03*
X108271D03*
X112208D03*
X116145D03*
X120083D03*
X124020D03*
X127957D03*
X131894D03*
X135831D03*
X139768D03*
X143705D03*
X147642D03*
X80712Y439690D03*
X84649D03*
X88586D03*
X92523D03*
X96460D03*
X100397D03*
X104334D03*
X108271D03*
X112208D03*
X116145D03*
X120083D03*
X124020D03*
X127957D03*
X131894D03*
X135831D03*
X139768D03*
X143705D03*
X147642D03*
X80712Y435753D03*
X84649D03*
X88586D03*
X92523D03*
X96460D03*
X100397D03*
X104334D03*
X108271D03*
X112208D03*
X116145D03*
X120083D03*
X124020D03*
X127957D03*
X131894D03*
X135831D03*
X139768D03*
X143705D03*
X147642D03*
X80712Y431816D03*
X84649D03*
X88586D03*
X92523D03*
X96460D03*
X100397D03*
X104334D03*
X108271D03*
X112208D03*
X116145D03*
X120083D03*
X124020D03*
X127957D03*
X131894D03*
X135831D03*
X139768D03*
X143705D03*
X147642D03*
X80712Y427879D03*
X84649D03*
X88586D03*
X92523D03*
X96460D03*
X100397D03*
X104334D03*
X108271D03*
X112208D03*
X116145D03*
X120083D03*
X124020D03*
X127957D03*
X131894D03*
X135831D03*
X139768D03*
X143705D03*
X147642D03*
X80712Y423942D03*
X84649D03*
X88586D03*
X92523D03*
X96460D03*
X100397D03*
X104334D03*
X108271D03*
X112208D03*
X116145D03*
X120083D03*
X124020D03*
X127957D03*
X131894D03*
X135831D03*
X139768D03*
X143705D03*
X147642D03*
X80712Y420005D03*
X84649D03*
X88586D03*
X92523D03*
X96460D03*
X100397D03*
X104334D03*
X108271D03*
X112208D03*
X116145D03*
X120083D03*
X124020D03*
X127957D03*
X131894D03*
X135831D03*
X139768D03*
X143705D03*
X147642D03*
X80712Y494809D03*
X84649D03*
X88586D03*
X92523D03*
X96460D03*
X100397D03*
X104334D03*
X108271D03*
X112208D03*
X116145D03*
X120083D03*
X124020D03*
X127957D03*
X131894D03*
X135831D03*
X139768D03*
X143705D03*
X147642D03*
X80712Y490872D03*
X84649D03*
X88586D03*
X92523D03*
X96460D03*
X100397D03*
X104334D03*
X108271D03*
X112208D03*
X116145D03*
X120083D03*
X124020D03*
X127957D03*
X131894D03*
X135831D03*
X139768D03*
X143705D03*
X147642D03*
X80712Y486935D03*
X84649D03*
X88586D03*
X92523D03*
X96460D03*
X100397D03*
X104334D03*
X108271D03*
X112208D03*
X116145D03*
X120083D03*
X124020D03*
X127957D03*
X131894D03*
X135831D03*
X139768D03*
X143705D03*
X147642D03*
X163390Y416068D03*
X167327D03*
X171264D03*
X163390Y412131D03*
X167327D03*
X171264D03*
X163390Y408194D03*
X167327D03*
X171264D03*
X163390Y404257D03*
X167327D03*
X171264D03*
X163390Y400320D03*
X167327D03*
X171264D03*
X151579Y416068D03*
X155516D03*
X159453D03*
X151579Y412131D03*
X155516D03*
X159453D03*
X151579Y408194D03*
X155516D03*
X159453D03*
X151579Y404257D03*
X155516D03*
X159453D03*
X151579Y400320D03*
X155516D03*
X159453D03*
X151579Y396383D03*
X155516D03*
X159453D03*
X151579Y392446D03*
X155516D03*
X159453D03*
X151579Y388509D03*
X155516D03*
X159453D03*
X163390Y482998D03*
X167327D03*
X171264D03*
X163390Y479061D03*
X167327D03*
X171264D03*
X163390Y475124D03*
X167327D03*
X171264D03*
X163390Y471187D03*
X167327D03*
X171264D03*
X163390Y467250D03*
X167327D03*
X171264D03*
X163390Y463313D03*
X167327D03*
X171264D03*
X163390Y459376D03*
X167327D03*
X171264D03*
X163390Y455439D03*
X167327D03*
X171264D03*
X163390Y451502D03*
X167327D03*
X171264D03*
X163390Y447565D03*
X167327D03*
X171264D03*
X163390Y443628D03*
X167327D03*
X171264D03*
X163390Y439690D03*
X167327D03*
X171264D03*
X163390Y435753D03*
X167327D03*
X171264D03*
X163390Y431816D03*
X167327D03*
X171264D03*
X163390Y427879D03*
X167327D03*
X171264D03*
X163390Y423942D03*
X167327D03*
X171264D03*
X163390Y420005D03*
X167327D03*
X171264D03*
X151579Y482998D03*
X155516D03*
X159453D03*
X151579Y479061D03*
X155516D03*
X159453D03*
X151579Y475124D03*
X155516D03*
X159453D03*
X151579Y471187D03*
X155516D03*
X159453D03*
X151579Y467250D03*
X155516D03*
X159453D03*
X151579Y463313D03*
X155516D03*
X159453D03*
X151579Y459376D03*
X155516D03*
X159453D03*
X151579Y455439D03*
X155516D03*
X159453D03*
X151579Y451502D03*
X155516D03*
X159453D03*
X151579Y447565D03*
X155516D03*
X159453D03*
X151579Y443628D03*
X155516D03*
X159453D03*
X151579Y439690D03*
X155516D03*
X159453D03*
X151579Y435753D03*
X155516D03*
X159453D03*
X151579Y431816D03*
X155516D03*
X159453D03*
X151579Y427879D03*
X155516D03*
X159453D03*
X151579Y423942D03*
X155516D03*
X159453D03*
X151579Y420005D03*
X155516D03*
X159453D03*
X151579Y494809D03*
X155516D03*
X159453D03*
X151579Y490872D03*
X155516D03*
X159453D03*
X151579Y486935D03*
X155516D03*
X159453D03*
G54D39*
X52900Y645300D03*
Y634300D03*
Y748300D03*
Y759300D03*
X205600Y135800D03*
Y146800D03*
X294751Y448610D03*
Y437610D03*
X303549Y448556D03*
Y437556D03*
G54D57*
X160359Y154160D03*
Y156128D03*
Y158097D03*
Y160066D03*
Y162034D03*
X174339D03*
Y160066D03*
Y158097D03*
Y156128D03*
Y154160D03*
G54D75*
X662514Y518651D03*
Y521210D03*
Y523769D03*
Y526328D03*
Y528887D03*
X682000D03*
Y526328D03*
Y523769D03*
Y521210D03*
Y518651D03*
G54D48*
X104382Y212614D03*
X99525Y212610D03*
X212700Y129700D03*
X168084Y172055D03*
X212492Y403033D03*
X217363Y401778D03*
X185934Y470229D03*
X203439Y459352D03*
X194624Y421463D03*
X190765Y470328D03*
X264353Y484934D03*
X222577Y522519D03*
X341430Y463151D03*
X371408Y393555D03*
X366586D03*
X361719D03*
G54D66*
X246455Y109757D03*
G54D58*
X167349Y158097D03*
G54D67*
X220569Y204940D03*
X223129D03*
X225689D03*
X228249D03*
Y188760D03*
X225689D03*
X223129D03*
X220569D03*
X237750Y428000D03*
X235250D03*
X232750D03*
X230250D03*
X227750D03*
X225250D03*
X222750D03*
X220250D03*
Y448600D03*
X222750D03*
X225250D03*
X227750D03*
X230250D03*
X232750D03*
X235250D03*
X237750D03*
X228249Y755690D03*
X225689D03*
X223129D03*
X220569D03*
Y771870D03*
X223129D03*
X225689D03*
X228249D03*
G54D76*
X667139Y533512D03*
X669698D03*
X672257D03*
X674816D03*
X677375D03*
Y514026D03*
X674816D03*
X672257D03*
X669698D03*
X667139D03*
G54D49*
X104382Y218214D03*
X99525Y218210D03*
X212700Y135300D03*
X168084Y177655D03*
X212492Y408633D03*
X217363Y407378D03*
X185934Y475829D03*
X203439Y464952D03*
X194624Y427063D03*
X190765Y475928D03*
X222577Y528119D03*
X264353Y490534D03*
X341430Y468751D03*
X371408Y399155D03*
X366586D03*
X361719D03*
G54D77*
X702989Y515755D03*
X691989D03*
X703000Y524500D03*
X692000D03*
G54D68*
X234222Y399876D03*
Y396136D03*
Y392396D03*
X243222D03*
Y399876D03*
G54D59*
X166649Y135347D03*
G54D78*
G01X-1003937Y-3937D02*
G03X-1000000Y-7874I3937J0D01*
G01X-1031496Y-31496D02*
G03X-1027559Y-35433I3937J0D01*
G01X-986221Y-7874D02*
G03Y0I0J3937D01*
G01Y-7874D02*
X-1000000D01*
G01X-1027559Y-35433D02*
X791338D01*
G01X-1031496Y95866D02*
Y-31496D01*
G01X-996063Y3937D02*
G03X-992126Y0I3937J0D01*
G01X-996063Y39370D02*
G03X-1003937I-3937J0D01*
G01X-996063Y3937D02*
G03X-992126Y0I3937J0D01*
G01D02*
X-318898D01*
G01D02*
X-992126D01*
G01X-955512D02*
X-986221D01*
G01X-996063Y3937D02*
Y103740D01*
G01Y39370D02*
Y70079D01*
G01X-1003937Y-3937D02*
Y39370D01*
G01X-1027559Y99803D02*
G03X-1031496Y95866I0J-3937D01*
G01X-1003937D02*
G03X-1007874Y99803I-3937J0D01*
G01X-996063Y103740D02*
G03X-1000000Y107677I-3937J0D01*
G01X-1003937Y70079D02*
G03X-996063I3937J0D01*
G01X-1029528Y107677D02*
X-1000000D01*
G01X-1007874Y99803D02*
X-1027559D01*
G01X-1003937Y70079D02*
Y95866D01*
G01X-1031496Y109646D02*
X-1029528Y107677D01*
G01X-1031496Y109646D02*
Y134055D01*
G01X-1002166Y136024D02*
G03Y143504I0J3740D01*
G01X-1000000Y187599D02*
G03X-996063Y191536I0J3937D01*
G01X-1029528Y187599D02*
X-1000000D01*
G01X-1029528Y143504D02*
X-1002166D01*
G01X-1029528Y136024D02*
X-1002166D01*
G01X-1029528D02*
X-1031496Y134055D01*
G01X-1029528Y187599D02*
X-1031496Y185630D01*
G01Y145473D02*
X-1029528Y143504D01*
G01X-996063Y261221D02*
Y191536D01*
G01X-1031496Y145473D02*
Y185630D01*
G01X-996063Y261221D02*
G03X-1000000Y265158I-3937J0D01*
G01X-1029528D02*
X-1000000D01*
G01X-1031496Y267126D02*
X-1029528Y265158D01*
G01X-1031496Y267126D02*
Y543504D01*
G01X-1002166Y545473D02*
G03Y552953I0J3740D01*
G01X-1029528D02*
X-1002166D01*
G01X-1029528Y545473D02*
X-1002166D01*
G01X-1031496Y554922D02*
X-1029528Y552953D01*
G01Y545473D02*
X-1031496Y543504D01*
G01Y554922D02*
Y595079D01*
G01X-1007874Y604922D02*
G03X-1003937Y608859I0J3937D01*
G01X-1031496D02*
G03X-1027559Y604922I3937J0D01*
G01X-1000000Y597048D02*
G03X-996063Y600985I0J3937D01*
G01X-1027559Y604922D02*
X-1007874D01*
G01X-1029528Y597048D02*
X-1000000D01*
G01X-1029528D02*
X-1031496Y595079D01*
G01X-996063Y921260D02*
Y600985D01*
G01X-1003937Y608859D02*
Y708662D01*
G01X-1031496Y956693D02*
Y608859D01*
G01X-1003937Y739370D02*
G03X-996063I3937J0D01*
G01Y708662D02*
G03X-1003937I-3937J0D01*
G01X-996063D02*
Y739370D01*
G01X-1003937D02*
Y929134D01*
G01X-992126Y925197D02*
G03X-996063Y921260I0J-3937D01*
G01X-1000000Y933071D02*
G03X-1003937Y929134I0J-3937D01*
G01X-986221Y925197D02*
G03Y933071I0J3937D01*
G01X-1027559Y960630D02*
G03X-1031496Y956693I0J-3937D01*
G01X-992126Y925197D02*
G03X-996063Y921260I0J-3937D01*
G01X791338Y960630D02*
X-1027559D01*
G01X-1000000Y933071D02*
X-986221D01*
G01X-992126Y925197D02*
X-240158D01*
G01X-986221D02*
X-955512D01*
G01X-992126D02*
X-240158D01*
G01X-955512Y0D02*
G03Y-7874I0J-3937D01*
G01X-769685D02*
X-955512D01*
G01Y933071D02*
G03Y925197I0J-3937D01*
G01Y933071D02*
X-750000D01*
G01X-769685Y-7874D02*
G03Y0I0J3937D01*
G01X-738977D02*
X-769685D01*
G01X-755164Y-252763D02*
Y-235263D01*
G01X-746868D02*
X-755164Y-246055D01*
G01X-745558Y-252763D02*
X-751453Y-241097D01*
G01X-737883Y-252763D02*
Y-235263D01*
X-727839Y-252763D01*
Y-235263D01*
G01X-715361Y-252763D02*
X-717108Y-252471D01*
X-718636Y-251305D01*
X-719946Y-249555D01*
X-720820Y-247513D01*
X-721256Y-245180D01*
Y-242846D01*
X-720820Y-240513D01*
X-719946Y-238471D01*
X-718636Y-236722D01*
X-717108Y-235555D01*
X-715361Y-235263D01*
X-713615Y-235555D01*
X-712086Y-236722D01*
X-710776Y-238471D01*
X-709902Y-240513D01*
X-709466Y-242846D01*
Y-245180D01*
X-709902Y-247513D01*
X-710776Y-249555D01*
X-712086Y-251305D01*
X-713615Y-252471D01*
X-715361Y-252763D01*
G01X-702446D02*
X-693276Y-235263D01*
G01X-702446D02*
X-693276Y-252763D01*
G01X-658494D02*
X-667228D01*
Y-235263D01*
X-658494D01*
G01X-661988Y-243721D02*
X-667228D01*
G01X-649946Y-252763D02*
X-640776Y-235263D01*
G01X-649946D02*
X-640776Y-252763D01*
G01X-632228D02*
Y-235263D01*
X-626988D01*
X-625241Y-236138D01*
X-623931Y-238180D01*
X-623494Y-240513D01*
X-623931Y-242846D01*
X-625023Y-244596D01*
X-626988Y-245472D01*
X-632228D01*
G01X-615820Y-252763D02*
X-610361Y-235263D01*
X-604902Y-252763D01*
G01X-606868Y-246638D02*
X-613855D01*
G01X-597883Y-252763D02*
Y-235263D01*
X-587839Y-252763D01*
Y-235263D01*
G01X-580164Y-252763D02*
Y-235263D01*
X-575798D01*
X-574051Y-236138D01*
X-572741Y-237305D01*
X-571649Y-239054D01*
X-570776Y-241097D01*
X-570558Y-244013D01*
X-570776Y-246930D01*
X-571649Y-248972D01*
X-572741Y-250722D01*
X-574051Y-251888D01*
X-575798Y-252763D01*
X-580164D01*
G01X-553494D02*
X-562228D01*
Y-235263D01*
X-553494D01*
G01X-556988Y-243721D02*
X-562228D01*
G01X-544728Y-252763D02*
Y-235263D01*
X-539269D01*
X-537523Y-236138D01*
X-536431Y-237305D01*
X-535994Y-239638D01*
X-536431Y-241972D01*
X-537741Y-243430D01*
X-539269Y-244305D01*
X-544728D01*
G01X-539269D02*
X-535994Y-252763D01*
G01X-503615Y-243430D02*
X-502741Y-242555D01*
X-502086Y-241097D01*
X-501649Y-239054D01*
X-502086Y-237305D01*
X-502959Y-236138D01*
X-504488Y-235263D01*
X-510383D01*
Y-252763D01*
X-503178D01*
X-501649Y-251597D01*
X-500776Y-249846D01*
X-500339Y-247805D01*
X-500776Y-245763D01*
X-502086Y-244013D01*
X-503615Y-243430D01*
X-510383D01*
G01X-487861Y-252763D02*
X-489608Y-252471D01*
X-491136Y-251305D01*
X-492446Y-249555D01*
X-493320Y-247513D01*
X-493756Y-245180D01*
Y-242846D01*
X-493320Y-240513D01*
X-492446Y-238471D01*
X-491136Y-236722D01*
X-489608Y-235555D01*
X-487861Y-235263D01*
X-486115Y-235555D01*
X-484586Y-236722D01*
X-483276Y-238471D01*
X-482402Y-240513D01*
X-481966Y-242846D01*
Y-245180D01*
X-482402Y-247513D01*
X-483276Y-249555D01*
X-484586Y-251305D01*
X-486115Y-252471D01*
X-487861Y-252763D01*
G01X-475820D02*
X-470361Y-235263D01*
X-464902Y-252763D01*
G01X-466868Y-246638D02*
X-473855D01*
G01X-457228Y-252763D02*
Y-235263D01*
X-451769D01*
X-450023Y-236138D01*
X-448931Y-237305D01*
X-448494Y-239638D01*
X-448931Y-241972D01*
X-450241Y-243430D01*
X-451769Y-244305D01*
X-457228D01*
G01X-451769D02*
X-448494Y-252763D01*
G01X-440164D02*
Y-235263D01*
X-435798D01*
X-434051Y-236138D01*
X-432741Y-237305D01*
X-431649Y-239054D01*
X-430776Y-241097D01*
X-430558Y-244013D01*
X-430776Y-246930D01*
X-431649Y-248972D01*
X-432741Y-250722D01*
X-434051Y-251888D01*
X-435798Y-252763D01*
X-440164D01*
G01X-738977Y0D02*
G03Y-7874I0J-3937D01*
G01X-522835D02*
X-738977D01*
G01X-719292Y933071D02*
G03Y925197I0J-3937D01*
G01X-750000D02*
G03Y933071I0J3937D01*
G01X-719292D02*
X-512992D01*
G01X-750000Y925197D02*
X-719292D01*
G01X-633538Y-207763D02*
Y-190263D01*
X-627861Y-204846D01*
X-622184Y-190263D01*
Y-207763D01*
G01X-610361D02*
X-611671Y-207471D01*
X-612981Y-206305D01*
X-613855Y-204263D01*
X-614291Y-201930D01*
X-613855Y-199596D01*
X-612981Y-197555D01*
X-611671Y-196388D01*
X-610361Y-196097D01*
X-609051Y-196388D01*
X-607741Y-197555D01*
X-606868Y-199596D01*
X-606649Y-201930D01*
X-606868Y-204263D01*
X-607741Y-206305D01*
X-609051Y-207471D01*
X-610361Y-207763D01*
G01X-588931Y-190263D02*
Y-207763D01*
G01Y-205139D02*
X-589804Y-206597D01*
X-591115Y-207471D01*
X-592643Y-207763D01*
X-594389Y-207180D01*
X-595699Y-205722D01*
X-596573Y-203972D01*
X-596791Y-201930D01*
X-596573Y-199888D01*
X-595699Y-198138D01*
X-594389Y-196680D01*
X-592643Y-196097D01*
X-591115Y-196388D01*
X-590023Y-196972D01*
X-588931Y-198138D01*
G01X-578636Y-199888D02*
X-571649D01*
X-572304Y-197846D01*
X-573396Y-196680D01*
X-574924Y-196097D01*
X-576453Y-196388D01*
X-577763Y-197263D01*
X-578636Y-199305D01*
X-579073Y-201055D01*
Y-202805D01*
X-578636Y-204555D01*
X-577544Y-206305D01*
X-576234Y-207471D01*
X-574706Y-207763D01*
X-573178Y-207180D01*
X-571649Y-205430D01*
G01X-557861Y-207763D02*
Y-190263D01*
G01X-522835Y-7874D02*
G03Y0I0J3937D01*
G01X-492126D02*
G03Y-7874I0J-3937D01*
G01X-365355D02*
X-492126D01*
G01Y0D02*
X-522835D01*
G01X-482284Y933071D02*
G03Y925197I0J-3937D01*
G01X-512992D02*
G03Y933071I0J3937D01*
G01Y925197D02*
X-482284D01*
G01Y933071D02*
X-316142D01*
G01X-380161Y-252763D02*
Y-235263D01*
X-382781Y-238763D01*
G01Y-252763D02*
X-377541D01*
G01X-366809Y-238180D02*
X-365499Y-236430D01*
X-363971Y-235555D01*
X-362224Y-235263D01*
X-360041Y-235846D01*
X-358513Y-237305D01*
X-358076Y-239054D01*
X-358294Y-240805D01*
X-359168Y-242263D01*
X-363534Y-245180D01*
X-365499Y-247221D01*
X-366809Y-250139D01*
X-367246Y-252763D01*
X-358076D01*
G01X-345161Y-235263D02*
X-346908Y-235846D01*
X-348218Y-237305D01*
X-349091Y-239054D01*
X-349746Y-241388D01*
X-349964Y-244013D01*
X-349746Y-246638D01*
X-349091Y-248972D01*
X-348218Y-250722D01*
X-346908Y-252180D01*
X-345161Y-252763D01*
X-343415Y-252180D01*
X-342104Y-250722D01*
X-341231Y-248972D01*
X-340576Y-246638D01*
X-340358Y-244013D01*
X-340576Y-241388D01*
X-341231Y-239054D01*
X-342104Y-237305D01*
X-343415Y-235846D01*
X-345161Y-235263D01*
G01X-327661D02*
X-329408Y-235846D01*
X-330718Y-237305D01*
X-331591Y-239054D01*
X-332246Y-241388D01*
X-332464Y-244013D01*
X-332246Y-246638D01*
X-331591Y-248972D01*
X-330718Y-250722D01*
X-329408Y-252180D01*
X-327661Y-252763D01*
X-325915Y-252180D01*
X-324604Y-250722D01*
X-323731Y-248972D01*
X-323076Y-246638D01*
X-322858Y-244013D01*
X-323076Y-241388D01*
X-323731Y-239054D01*
X-324604Y-237305D01*
X-325915Y-235846D01*
X-327661Y-235263D01*
G01X-307541Y-252763D02*
Y-235263D01*
X-315620Y-247805D01*
X-304702D01*
G01X-393278Y-207763D02*
Y-190263D01*
X-388038D01*
X-386291Y-191138D01*
X-384981Y-193180D01*
X-384544Y-195513D01*
X-384981Y-197846D01*
X-386073Y-199596D01*
X-388038Y-200472D01*
X-393278D01*
G01X-366608Y-191722D02*
X-367918Y-190846D01*
X-369446Y-190263D01*
X-371193D01*
X-373158Y-191138D01*
X-374686Y-192596D01*
X-375778Y-194347D01*
X-376651Y-197263D01*
X-376870Y-199888D01*
X-376433Y-202513D01*
X-375778Y-204263D01*
X-374468Y-206013D01*
X-372939Y-207180D01*
X-371411Y-207763D01*
X-369883D01*
X-368354Y-207180D01*
X-367044Y-206305D01*
X-365952Y-205139D01*
G01X-352165Y-198430D02*
X-351291Y-197555D01*
X-350636Y-196097D01*
X-350199Y-194054D01*
X-350636Y-192305D01*
X-351509Y-191138D01*
X-353038Y-190263D01*
X-358933D01*
Y-207763D01*
X-351728D01*
X-350199Y-206597D01*
X-349326Y-204846D01*
X-348889Y-202805D01*
X-349326Y-200763D01*
X-350636Y-199013D01*
X-352165Y-198430D01*
X-358933D01*
G01X-342961Y-213596D02*
X-329861D01*
G01X-323933Y-207763D02*
Y-190263D01*
X-313889Y-207763D01*
Y-190263D01*
G01X-301411Y-207763D02*
X-303158Y-207471D01*
X-304686Y-206305D01*
X-305996Y-204555D01*
X-306870Y-202513D01*
X-307306Y-200180D01*
Y-197846D01*
X-306870Y-195513D01*
X-305996Y-193471D01*
X-304686Y-191722D01*
X-303158Y-190555D01*
X-301411Y-190263D01*
X-299665Y-190555D01*
X-298136Y-191722D01*
X-296826Y-193471D01*
X-295952Y-195513D01*
X-295516Y-197846D01*
Y-200180D01*
X-295952Y-202513D01*
X-296826Y-204555D01*
X-298136Y-206305D01*
X-299665Y-207471D01*
X-301411Y-207763D01*
G01X-365355Y-7874D02*
G03Y0I0J3937D01*
G01X-334646D02*
X-365355D01*
G01X-311024Y-7874D02*
G03X-307087Y-3937I0J3937D01*
G01X-334646Y0D02*
G03Y-7874I0J-3937D01*
G01X-311024D02*
X-334646D01*
G01X-318898Y0D02*
G03X-314961Y3937I0J3937D01*
G01X-274410Y31595D02*
G03X-270473Y35532I0J3937D01*
G01X-303150Y31595D02*
G03X-307087Y27658I0J-3937D01*
G01X-318898Y0D02*
G03X-314961Y3937I0J3937D01*
G01X-307087Y27658D02*
Y-3937D01*
G01X-314961Y133859D02*
Y3937D01*
G01Y133859D02*
Y3937D01*
G01X-274410Y31595D02*
X-303150D01*
G01X-311024Y137796D02*
G03X-314961Y133859I0J-3937D01*
G01X-311024Y137796D02*
G03X-314961Y133859I0J-3937D01*
G01X-240158Y137796D02*
X-311024D01*
G01X-240158D02*
X-311024D01*
G01X-285433Y933071D02*
G03Y925197I0J-3937D01*
G01X-316142D02*
G03Y933071I0J3937D01*
G01X-285433D02*
X-224410D01*
G01X-316142Y925197D02*
X-285433D01*
G01X-218861Y-252763D02*
Y-235263D01*
X-221481Y-238763D01*
G01Y-252763D02*
X-216241D01*
G01X-250570Y-190263D02*
X-245111Y-207763D01*
X-239652Y-190263D01*
G01X-223244Y-207763D02*
X-231978D01*
Y-190263D01*
X-223244D01*
G01X-226738Y-198721D02*
X-231978D01*
G01X-214478Y-207763D02*
Y-190263D01*
X-209019D01*
X-207273Y-191138D01*
X-206181Y-192305D01*
X-205744Y-194638D01*
X-206181Y-196972D01*
X-207491Y-198430D01*
X-209019Y-199305D01*
X-214478D01*
G01X-209019D02*
X-205744Y-207763D01*
G01X-192611Y-208346D02*
X-193048Y-208055D01*
Y-207471D01*
X-192611Y-207180D01*
X-192174Y-207471D01*
Y-208055D01*
X-192611Y-208346D01*
G01X-270473Y125985D02*
Y35532D01*
G01X-266536Y129922D02*
G03X-270473Y125985I0J-3937D01*
G01X-260630Y129922D02*
G03Y137796I0J3937D01*
G01X-244882D02*
G03Y129922I0J-3937D01*
G01X-240158D02*
G03X-228347Y141733I0J11811D01*
G01X-260630Y129922D02*
X-266536D01*
G01X-240158D02*
X-244882D01*
G01X-240158Y137796D02*
G03X-236221Y141733I0J3937D01*
G01X-240158Y137796D02*
G03X-236221Y141733I0J3937D01*
G01X-228347Y368701D02*
Y141733D01*
G01X-236221Y413386D02*
Y141733D01*
G01X-244882Y137796D02*
X-260630D01*
G01X-204725Y409449D02*
G03X-208662Y405512I0J-3937D01*
G01X-232284Y417323D02*
G03X-236221Y413386I0J-3937D01*
G01X-232284Y417323D02*
G03X-236221Y413386I0J-3937D01*
G01X-212599Y372638D02*
G03X-208662Y376575I0J3937D01*
G01X-224410Y372638D02*
G03X-228347Y368701I0J-3937D01*
G01X-181103Y409449D02*
X-204725D01*
G01X-212599Y372638D02*
X-224410D01*
G01X-208662Y405512D02*
Y376575D01*
G01X-232284Y417323D02*
X-181103D01*
G01X-232284D02*
X-181103D01*
G01X-236221Y716536D02*
G03X-232284Y712599I3937J0D01*
G01X-224410Y724410D02*
G03X-220473Y720473I3937J0D01*
G01X-236221Y716536D02*
G03X-232284Y712599I3937J0D01*
G01X-220473Y720473D02*
X-96418D01*
G01Y712599D02*
X-232284D01*
G01X-96418D02*
X-232284D01*
G01X-224410Y933071D02*
Y724410D01*
G01X-236221Y921260D02*
Y716536D01*
G01Y921260D02*
G03X-240158Y925197I-3937J0D01*
G01X-236221Y921260D02*
G03X-240158Y925197I-3937J0D01*
G01X-143740Y216536D02*
G03X-139803Y212599I3937J0D01*
G01X-143740Y262205D02*
G03X-151614I-3937J0D01*
G01X-143740Y216536D02*
G03X-139803Y212599I3937J0D01*
G01X-151614Y216536D02*
G03X-139803Y204725I11811J0D01*
G01X-143740Y262205D02*
Y292914D01*
G01Y338583D02*
Y216536D01*
G01Y338583D02*
Y216536D01*
G01X-151614D02*
Y262205D01*
G01X-139803Y212599D02*
X-3937D01*
G01X-139803D02*
X-3937D01*
G01X-15748Y204725D02*
X-139803D01*
G01Y342520D02*
G03X-143740Y338583I0J-3937D01*
G01X-139803Y342520D02*
G03X-143740Y338583I0J-3937D01*
G01X-139803Y350394D02*
G03X-151614Y338583I0J-11811D01*
G01Y292914D02*
G03X-143740I3937J0D01*
G01X-151614D02*
Y338583D01*
G01X-62992Y342520D02*
X-139803D01*
G01X-62992D02*
X-139803D01*
G01X-181103Y409449D02*
G03X-169292Y421260I0J11811D01*
G01X-139803Y350394D02*
X-70866D01*
G01X-177166Y467717D02*
G03X-169292I3937J0D01*
G01X-181103Y417323D02*
G03X-177166Y421260I0J3937D01*
G01X-169292Y437008D02*
G03X-177166I-3937J0D01*
G01X-181103Y417323D02*
G03X-177166Y421260I0J3937D01*
G01X-169292Y437008D02*
Y421260D01*
G01Y570866D02*
Y467717D01*
G01X-177166Y421260D02*
Y578740D01*
G01Y421260D02*
Y578740D01*
G01Y467717D02*
Y437008D01*
G01X-173229Y582677D02*
G03X-177166Y578740I0J-3937D01*
G01X-165355Y574803D02*
G03X-169292Y570866I0J-3937D01*
G01X-173229Y582677D02*
G03X-177166Y578740I0J-3937D01*
G01X-173229Y582677D02*
X-96418D01*
G01X-173229D02*
X-96418D01*
G01Y574803D02*
X-165355D01*
G01X-103911Y-235263D02*
Y-252763D01*
G01X-108933Y-235263D02*
X-98889D01*
G01X-90996Y-250430D02*
X-89249Y-251888D01*
X-87284Y-252763D01*
X-85538D01*
X-83791Y-251888D01*
X-82481Y-250430D01*
X-81826Y-248388D01*
X-82263Y-246347D01*
X-83354Y-244596D01*
X-85319Y-243430D01*
X-87939Y-242846D01*
X-89468Y-241680D01*
X-90123Y-239638D01*
X-89686Y-237596D01*
X-88594Y-236138D01*
X-87066Y-235263D01*
X-85538D01*
X-84009Y-235846D01*
X-82699Y-237305D01*
G01X-74588Y-252763D02*
Y-235263D01*
X-68911Y-249846D01*
X-63234Y-235263D01*
Y-252763D01*
G01X-56214D02*
Y-235263D01*
X-51848D01*
X-50101Y-236138D01*
X-48791Y-237305D01*
X-47699Y-239054D01*
X-46826Y-241097D01*
X-46608Y-244013D01*
X-46826Y-246930D01*
X-47699Y-248972D01*
X-48791Y-250722D01*
X-50101Y-251888D01*
X-51848Y-252763D01*
X-56214D01*
G01X-125778Y-190263D02*
Y-207763D01*
X-117044D01*
G01X-99981D02*
Y-196097D01*
G01Y-198138D02*
X-100854Y-196972D01*
X-102165Y-196388D01*
X-103693Y-196097D01*
X-105221Y-196680D01*
X-106531Y-197846D01*
X-107405Y-199596D01*
X-107841Y-201930D01*
X-107405Y-204263D01*
X-106531Y-206013D01*
X-105221Y-207180D01*
X-103693Y-207763D01*
X-102165Y-207471D01*
X-100854Y-206597D01*
X-99981Y-205430D01*
G01X-90996Y-213013D02*
X-89686Y-213596D01*
X-87939Y-213013D01*
X-86848Y-211847D01*
X-85974Y-210388D01*
X-84665Y-205722D01*
X-81826Y-196097D01*
G01X-88813D02*
X-84665Y-205722D01*
G01X-72186Y-199888D02*
X-65199D01*
X-65854Y-197846D01*
X-66946Y-196680D01*
X-68474Y-196097D01*
X-70003Y-196388D01*
X-71313Y-197263D01*
X-72186Y-199305D01*
X-72623Y-201055D01*
Y-202805D01*
X-72186Y-204555D01*
X-71094Y-206305D01*
X-69784Y-207471D01*
X-68256Y-207763D01*
X-66728Y-207180D01*
X-65199Y-205430D01*
G01X-54468Y-207763D02*
Y-196097D01*
G01Y-198430D02*
X-53376Y-197263D01*
X-52284Y-196388D01*
X-50756Y-196097D01*
X-49665Y-196388D01*
X-48354Y-197263D01*
G01X-37186Y-205722D02*
X-36094Y-206888D01*
X-34566Y-207763D01*
X-33256D01*
X-31946Y-207180D01*
X-31073Y-206305D01*
X-30636Y-205139D01*
X-30854Y-203388D01*
X-31728Y-202513D01*
X-35658Y-200763D01*
X-36531Y-198721D01*
X-36094Y-197263D01*
X-35221Y-196388D01*
X-33911Y-196097D01*
X-32601Y-196388D01*
X-31291Y-197263D01*
G01X-62992Y342520D02*
G03X-59055Y346457I0J3937D01*
G01X-62992Y342520D02*
G03X-59055Y346457I0J3937D01*
G01X-70866Y350394D02*
G03X-66929Y354331I0J3937D01*
G01D02*
Y457481D01*
G01Y488189D02*
G03X-59055I3937J0D01*
G01Y457481D02*
G03X-66929I-3937J0D01*
G01X-55118Y515748D02*
G03X-66929Y503937I0J-11811D01*
G01Y488189D02*
Y503937D01*
G01X-96418Y582677D02*
G03X-92481Y586615I0J3937D01*
G01X-96418Y582677D02*
G03X-92481Y586615I0J3937D01*
G01X-96418Y574803D02*
G03X-84607Y586615I0J11811D01*
G01Y632284D02*
Y586615D01*
G01X-92481D02*
Y708662D01*
G01Y586615D02*
Y708662D01*
G01Y662992D02*
G03X-84607I3937J0D01*
G01Y632284D02*
G03X-92481I-3937J0D01*
G01X-84607Y708662D02*
Y662992D01*
G01X-92481D02*
Y632284D01*
G01Y708662D02*
G03X-96418Y712599I-3937J0D01*
G01X-92481Y708662D02*
G03X-96418Y712599I-3937J0D01*
G01X-84607Y708662D02*
G03X-96418Y720473I-11811J0D01*
G01X-11811Y-3937D02*
G03X-7874Y-7874I3937J0D01*
G01X31496D02*
X-7874D01*
G01X0Y3937D02*
G03X3937Y0I3937J0D01*
G01X0Y3937D02*
G03X3937Y0I3937J0D01*
G01X0Y3937D02*
Y208662D01*
G01X-11811Y-3937D02*
Y200788D01*
G01X755905Y0D02*
X3937D01*
G01X755905D02*
X3937D01*
G01X-11811Y200788D02*
G03X-15748Y204725I-3937J0D01*
G01X0Y208662D02*
G03X-3937Y212599I-3937J0D01*
G01X0Y208662D02*
G03X-3937Y212599I-3937J0D01*
G01X-59055Y503937D02*
Y346457D01*
G01Y503937D02*
Y346457D01*
G01Y488189D02*
Y457481D01*
G01X-23622Y552559D02*
G03X-27559Y548622I0J-3937D01*
G01X-11811Y552559D02*
G03X-7874Y556496I0J3937D01*
G01X-3937Y507874D02*
G03X0Y511811I0J3937D01*
G01X-3937Y507874D02*
G03X0Y511811I0J3937D01*
G01X-55118Y507874D02*
G03X-59055Y503937I0J-3937D01*
G01X-31496Y515748D02*
G03X-27559Y519685I0J3937D01*
G01X-55118Y507874D02*
G03X-59055Y503937I0J-3937D01*
G01X-23622Y552559D02*
X-11811D01*
G01X0Y511811D02*
Y783465D01*
G01X-27559Y519685D02*
Y548622D01*
G01X-55118Y515748D02*
X-31496D01*
G01X-3937Y507874D02*
X-55118D01*
G01X-3937D02*
X-55118D01*
G01X-7874Y556496D02*
Y783465D01*
G01X3937Y787402D02*
G03X0Y783465I0J-3937D01*
G01X3937Y787402D02*
G03X0Y783465I0J-3937D01*
G01X3937Y795276D02*
G03X-7874Y783465I0J-11811D01*
G01X3937Y795276D02*
X8661D01*
G01X3937Y787402D02*
X74803D01*
G01X3937D02*
X74803D01*
G01X51772Y-235263D02*
Y-252763D01*
X60506D01*
G01X68836Y-235263D02*
Y-247805D01*
X69709Y-250430D01*
X71456Y-252180D01*
X73639Y-252763D01*
X75822Y-252180D01*
X77569Y-250430D01*
X78442Y-247805D01*
Y-235263D01*
G01X95942Y-236722D02*
X94632Y-235846D01*
X93104Y-235263D01*
X91357D01*
X89392Y-236138D01*
X87864Y-237596D01*
X86772Y-239347D01*
X85899Y-242263D01*
X85680Y-244888D01*
X86117Y-247513D01*
X86772Y-249263D01*
X88082Y-251013D01*
X89611Y-252180D01*
X91139Y-252763D01*
X92667D01*
X94196Y-252180D01*
X95506Y-251305D01*
X96598Y-250139D01*
G01X103836Y-252763D02*
Y-235263D01*
G01X112132D02*
X103836Y-246055D01*
G01X113442Y-252763D02*
X107547Y-241097D01*
G01X126139Y-252763D02*
Y-244888D01*
X121772Y-235263D01*
G01X130506D02*
X126139Y-244888D01*
G01X25086Y-207763D02*
Y-190263D01*
X29452D01*
X31199Y-191138D01*
X32509Y-192305D01*
X33601Y-194054D01*
X34474Y-196097D01*
X34692Y-199013D01*
X34474Y-201930D01*
X33601Y-203972D01*
X32509Y-205722D01*
X31199Y-206888D01*
X29452Y-207763D01*
X25086D01*
G01X44114Y-199888D02*
X51101D01*
X50446Y-197846D01*
X49354Y-196680D01*
X47826Y-196097D01*
X46297Y-196388D01*
X44987Y-197263D01*
X44114Y-199305D01*
X43677Y-201055D01*
Y-202805D01*
X44114Y-204555D01*
X45206Y-206305D01*
X46516Y-207471D01*
X48044Y-207763D01*
X49572Y-207180D01*
X51101Y-205430D01*
G01X61614Y-205722D02*
X62706Y-206888D01*
X64234Y-207763D01*
X65544D01*
X66854Y-207180D01*
X67727Y-206305D01*
X68164Y-205139D01*
X67946Y-203388D01*
X67072Y-202513D01*
X63142Y-200763D01*
X62269Y-198721D01*
X62706Y-197263D01*
X63579Y-196388D01*
X64889Y-196097D01*
X66199Y-196388D01*
X67509Y-197263D01*
G01X82389Y-196097D02*
Y-207763D01*
G01Y-191430D02*
X81952Y-191138D01*
Y-190555D01*
X82389Y-190263D01*
X82826Y-190555D01*
Y-191138D01*
X82389Y-191430D01*
G01X96832Y-212138D02*
X98361Y-213305D01*
X100107Y-213596D01*
X101635Y-213305D01*
X102946Y-211847D01*
X103819Y-209805D01*
Y-196097D01*
G01Y-198430D02*
X102946Y-197263D01*
X101635Y-196388D01*
X100107Y-196097D01*
X98361Y-196680D01*
X97269Y-197846D01*
X96395Y-199888D01*
X95959Y-201930D01*
X96177Y-203680D01*
X97051Y-205722D01*
X98361Y-207180D01*
X100107Y-207763D01*
X101417Y-207471D01*
X102946Y-206305D01*
X103819Y-205139D01*
G01X113677Y-207763D02*
Y-196097D01*
G01Y-199013D02*
X114551Y-197555D01*
X115861Y-196388D01*
X117607Y-196097D01*
X119135Y-196388D01*
X120446Y-197555D01*
X121101Y-199596D01*
Y-207763D01*
G01X131614Y-199888D02*
X138601D01*
X137946Y-197846D01*
X136854Y-196680D01*
X135326Y-196097D01*
X133797Y-196388D01*
X132487Y-197263D01*
X131614Y-199305D01*
X131177Y-201055D01*
Y-202805D01*
X131614Y-204555D01*
X132706Y-206305D01*
X134016Y-207471D01*
X135544Y-207763D01*
X137072Y-207180D01*
X138601Y-205430D01*
G01X149332Y-207763D02*
Y-196097D01*
G01Y-198430D02*
X150424Y-197263D01*
X151516Y-196388D01*
X153044Y-196097D01*
X154135Y-196388D01*
X155446Y-197263D01*
G01X62204Y0D02*
G03Y-7874I0J-3937D01*
G01X31496D02*
G03Y0I0J3937D01*
G01X267716Y-7874D02*
X62204D01*
G01Y0D02*
X31496D01*
G01X74803Y787402D02*
G03X78740Y791339I0J3937D01*
G01X30315Y795276D02*
G03X34252Y799213I0J3937D01*
G01X24409Y795276D02*
G03Y787402I0J-3937D01*
G01X8661D02*
G03Y795276I0J3937D01*
G01X74803Y787402D02*
G03X78740Y791339I0J3937D01*
G01X24409Y795276D02*
X30315D01*
G01X24409Y787402D02*
X8661D01*
G01X34252Y799213D02*
Y889666D01*
G01X38189Y893603D02*
G03X34252Y889666I0J-3937D01*
G01X66929Y893603D02*
G03X70866Y897540I0J3937D01*
G01X38189Y893603D02*
X66929D01*
G01X70866Y897540D02*
Y929134D01*
G01X74803Y933071D02*
G03X70866Y929134I0J-3937D01*
G01X74803Y933071D02*
X88582D01*
G01X78740Y791339D02*
Y921260D01*
G01Y791339D02*
Y921260D01*
G01X119291Y933071D02*
G03Y925197I0J-3937D01*
G01X82677D02*
G03X78740Y921260I0J-3937D01*
G01X88582Y925197D02*
G03Y933071I0J3937D01*
G01X82677Y925197D02*
G03X78740Y921260I0J-3937D01*
G01X119291Y933071D02*
X305118D01*
G01X82677Y925197D02*
X755905D01*
G01X82677D02*
X755905D01*
G01X119291D02*
X88582D01*
G01X196089Y-252763D02*
Y-235263D01*
X193469Y-238763D01*
G01Y-252763D02*
X198709D01*
G01X213589Y-235263D02*
X211842Y-235846D01*
X210532Y-237305D01*
X209659Y-239054D01*
X209004Y-241388D01*
X208786Y-244013D01*
X209004Y-246638D01*
X209659Y-248972D01*
X210532Y-250722D01*
X211842Y-252180D01*
X213589Y-252763D01*
X215335Y-252180D01*
X216646Y-250722D01*
X217519Y-248972D01*
X218174Y-246638D01*
X218392Y-244013D01*
X218174Y-241388D01*
X217519Y-239054D01*
X216646Y-237305D01*
X215335Y-235846D01*
X213589Y-235263D01*
G01X227159Y-253346D02*
X235019Y-235263D01*
G01X248589Y-252763D02*
Y-235263D01*
X245969Y-238763D01*
G01Y-252763D02*
X251209D01*
G01X261941Y-245472D02*
X263469Y-243430D01*
X264779Y-242263D01*
X266526Y-241680D01*
X268054Y-242263D01*
X269146Y-243430D01*
X270019Y-245180D01*
X270237Y-247221D01*
X270019Y-248972D01*
X269146Y-250722D01*
X267835Y-252180D01*
X266307Y-252763D01*
X264561Y-252180D01*
X263032Y-250430D01*
X262159Y-247805D01*
X261941Y-244888D01*
X262377Y-241097D01*
X263032Y-239054D01*
X264124Y-237013D01*
X265652Y-235555D01*
X267181Y-235263D01*
X268709Y-235846D01*
X269801Y-237305D01*
G01X279659Y-253346D02*
X287519Y-235263D01*
G01X296941Y-238180D02*
X298251Y-236430D01*
X299779Y-235555D01*
X301526Y-235263D01*
X303709Y-235846D01*
X305237Y-237305D01*
X305674Y-239054D01*
X305456Y-240805D01*
X304582Y-242263D01*
X300216Y-245180D01*
X298251Y-247221D01*
X296941Y-250139D01*
X296504Y-252763D01*
X305674D01*
G01X318589Y-235263D02*
X316842Y-235846D01*
X315532Y-237305D01*
X314659Y-239054D01*
X314004Y-241388D01*
X313786Y-244013D01*
X314004Y-246638D01*
X314659Y-248972D01*
X315532Y-250722D01*
X316842Y-252180D01*
X318589Y-252763D01*
X320335Y-252180D01*
X321646Y-250722D01*
X322519Y-248972D01*
X323174Y-246638D01*
X323392Y-244013D01*
X323174Y-241388D01*
X322519Y-239054D01*
X321646Y-237305D01*
X320335Y-235846D01*
X318589Y-235263D01*
G01X336089Y-252763D02*
Y-235263D01*
X333469Y-238763D01*
G01Y-252763D02*
X338709D01*
G01X349441Y-238180D02*
X350751Y-236430D01*
X352279Y-235555D01*
X354026Y-235263D01*
X356209Y-235846D01*
X357737Y-237305D01*
X358174Y-239054D01*
X357956Y-240805D01*
X357082Y-242263D01*
X352716Y-245180D01*
X350751Y-247221D01*
X349441Y-250139D01*
X349004Y-252763D01*
X358174D01*
G01X243786Y-207763D02*
Y-190263D01*
X248152D01*
X249899Y-191138D01*
X251209Y-192305D01*
X252301Y-194054D01*
X253174Y-196097D01*
X253392Y-199013D01*
X253174Y-201930D01*
X252301Y-203972D01*
X251209Y-205722D01*
X249899Y-206888D01*
X248152Y-207763D01*
X243786D01*
G01X270019D02*
Y-196097D01*
G01Y-198138D02*
X269146Y-196972D01*
X267835Y-196388D01*
X266307Y-196097D01*
X264779Y-196680D01*
X263469Y-197846D01*
X262595Y-199596D01*
X262159Y-201930D01*
X262595Y-204263D01*
X263469Y-206013D01*
X264779Y-207180D01*
X266307Y-207763D01*
X267835Y-207471D01*
X269146Y-206597D01*
X270019Y-205430D01*
G01X283589Y-190263D02*
Y-207763D01*
G01X280532Y-196097D02*
X286646D01*
G01X297814Y-199888D02*
X304801D01*
X304146Y-197846D01*
X303054Y-196680D01*
X301526Y-196097D01*
X299997Y-196388D01*
X298687Y-197263D01*
X297814Y-199305D01*
X297377Y-201055D01*
Y-202805D01*
X297814Y-204555D01*
X298906Y-206305D01*
X300216Y-207471D01*
X301744Y-207763D01*
X303272Y-207180D01*
X304801Y-205430D01*
G01X267716Y-7874D02*
G03Y0I0J3937D01*
G01X298425D02*
X267716D01*
G01X298425D02*
G03Y-7874I0J-3937D01*
G01X483071D02*
X298425D01*
G01X335827Y933071D02*
G03Y925197I0J-3937D01*
G01X305118D02*
G03Y933071I0J3937D01*
G01X335827D02*
X522441D01*
G01X335827Y925197D02*
X305118D01*
G01X483071Y-7874D02*
G03Y0I0J3937D01*
G01X513779D02*
X483071D01*
G01X513779D02*
G03Y-7874I0J-3937D01*
G01X719291D02*
X513779D01*
G01X553149Y933071D02*
G03Y925197I0J-3937D01*
G01X522441D02*
G03Y933071I0J3937D01*
G01X553149D02*
X719291D01*
G01X553149Y925197D02*
X522441D01*
G01X763779Y-7874D02*
G03X767716Y-3937I0J3937D01*
G01X719291Y-7874D02*
G03Y0I0J3937D01*
G01X750000D02*
G03Y-7874I0J-3937D01*
G01X763779D02*
X750000D01*
G01X755905Y0D02*
G03X759842Y3937I0J3937D01*
G01X755905Y0D02*
G03X759842Y3937I0J3937D01*
G01X767716Y185827D02*
Y-3937D01*
G01X759842Y3937D02*
Y324213D01*
G01X750000Y0D02*
X719291D01*
G01X767716Y185827D02*
G03X759842I-3937J0D01*
G01Y216536D02*
Y185827D01*
G01Y216536D02*
G03X767716I3937J0D01*
G01Y316339D02*
Y216536D01*
G01X771653Y320276D02*
G03X767716Y316339I0J-3937D01*
G01X763779Y328150D02*
G03X759842Y324213I0J-3937D01*
G01X793307Y328150D02*
X763779D01*
G01X791338Y320276D02*
X771653D01*
G01X765945Y379725D02*
G03Y372244I0J-3741D01*
G01X793307Y379725D02*
X765945D01*
G01X793307Y372244D02*
X765945D01*
G01X759842Y663977D02*
G03X763779Y660040I3937J0D01*
G01X759842Y663977D02*
Y733662D01*
G01X793307Y660040D02*
X763779D01*
G01Y737599D02*
G03X759842Y733662I0J-3937D01*
G01X793307Y737599D02*
X763779D01*
G01X765945Y789174D02*
G03Y781693I0J-3740D01*
G01X767716Y829331D02*
G03X771653Y825394I3937J0D01*
G01X759842Y821457D02*
G03X763779Y817520I3937J0D01*
G01X767716Y855118D02*
Y829331D01*
G01X759842Y921260D02*
Y821457D01*
G01X771653Y825394D02*
X791338D01*
G01X793307Y817520D02*
X763779D01*
G01X793307Y789174D02*
X765945D01*
G01X793307Y781693D02*
X765945D01*
G01X767716Y855118D02*
G03X759842I-3937J0D01*
G01Y885827D02*
G03X767716I3937J0D01*
G01Y929134D02*
Y885827D01*
G01X759842D02*
Y855118D01*
G01Y921260D02*
G03X755905Y925197I-3937J0D01*
G01X767716Y929134D02*
G03X763779Y933071I-3937J0D01*
G01X750000D02*
G03Y925197I0J-3937D01*
G01X719291D02*
G03Y933071I0J3937D01*
G01X759842Y921260D02*
G03X755905Y925197I-3937J0D01*
G01X750000Y933071D02*
X763779D01*
G01X750000Y925197D02*
X719291D01*
G01X791338Y-35433D02*
G03X795275Y-31496I0J3937D01*
G01D02*
Y316339D01*
G01D02*
G03X791338Y320276I-3937J0D01*
G01X795275Y370276D02*
Y330118D01*
G01D02*
X793307Y328150D01*
G01X795275Y658071D02*
Y381693D01*
G01D02*
X793307Y379725D01*
G01X795275Y370276D02*
X793307Y372244D01*
G01X795275Y658071D02*
X793307Y660040D01*
G01X795275Y779725D02*
Y739567D01*
G01D02*
X793307Y737599D01*
G01X791338Y825394D02*
G03X795275Y829331I0J3937D01*
G01D02*
Y956693D01*
G01Y815552D02*
Y791142D01*
G01Y815552D02*
X793307Y817520D01*
G01X795275Y779725D02*
X793307Y781693D01*
G01X795275Y791142D02*
X793307Y789174D01*
G01X795275Y956693D02*
G03X791338Y960630I-3937J0D01*
G54D69*
X268768Y415628D03*
Y430628D03*
M02*
